(kicad_sch
	(version 20250114)
	(generator "eeschema")
	(generator_version "9.0")
	(paper "A3")
	(title_block
		(title "PolarFire SoM")
		(date "2025-07-22")
		(rev "1.1.4")
		(company "Antmicro Ltd")
		(comment 1 "www.antmicro.com")
	)
	(bus_alias "I^{2}C"
		(members "SDA" "SCL")
	)
	(bus_alias "MDI"
		(members "TXRX_A_P" "TXRX_A_N" "TXRX_B_P" "TXRX_B_N" "TXRX_C_P" "TXRX_C_N"
			"TXRX_D_P" "TXRX_D_N" "LED[0..2]" "SYNC_IN" "SYNC_OUT"
		)
	)
	(bus_alias "SDIO"
		(members "DAT[0..7]" "CMD" "CLK" "STRB" "RST_n" "CD")
	)
	(text "RPI_GPIO25"
		(exclude_from_sim no)
		(at 162.56 129.54 0)
		(effects
			(font
				(size 1.27 1.27)
			)
			(justify right bottom)
		)
	)
	(text "UART5_TX/RPI_GPIO13"
		(exclude_from_sim no)
		(at 254 111.76 0)
		(effects
			(font
				(size 1.27 1.27)
			)
			(justify left bottom)
		)
	)
	(text "GPIO_VREF"
		(exclude_from_sim no)
		(at 241.3 175.26 0)
		(effects
			(font
				(size 1.27 1.27)
			)
			(justify left bottom)
		)
	)
	(text "Ethernet_SYNC_OUT"
		(exclude_from_sim no)
		(at 238.125 97.79 0)
		(effects
			(font
				(size 1.27 1.27)
			)
			(justify left bottom)
		)
	)
	(text "Ethernet_SYNC_IN"
		(exclude_from_sim no)
		(at 238.125 95.25 0)
		(effects
			(font
				(size 1.27 1.27)
			)
			(justify left bottom)
		)
	)
	(text "Ethernet_Pair0_N"
		(exclude_from_sim no)
		(at 238.125 87.63 0)
		(effects
			(font
				(size 1.27 1.27)
			)
			(justify left bottom)
		)
	)
	(text "SPI6_MOSI/RPI_GPIO20"
		(exclude_from_sim no)
		(at 163.83 111.76 0)
		(effects
			(font
				(size 1.27 1.27)
			)
			(justify right bottom)
		)
	)
	(text "RPI_ID_SD"
		(exclude_from_sim no)
		(at 285.115 121.285 0)
		(effects
			(font
				(size 1.27 1.27)
			)
			(justify left bottom)
		)
	)
	(text "SD_DAT5"
		(exclude_from_sim no)
		(at 280.67 156.21 0)
		(effects
			(font
				(size 1.27 1.27)
			)
			(justify left bottom)
		)
	)
	(text "RPI_GPIO06"
		(exclude_from_sim no)
		(at 254 114.3 0)
		(effects
			(font
				(size 1.27 1.27)
			)
			(justify left bottom)
		)
	)
	(text "Ethernet_Pair3_P"
		(exclude_from_sim no)
		(at 177.8 79.375 0)
		(effects
			(font
				(size 1.27 1.27)
			)
			(justify right bottom)
		)
	)
	(text "AnalogIP1"
		(exclude_from_sim no)
		(at 222.25 195.58 0)
		(effects
			(font
				(size 1.27 1.27)
			)
			(justify left bottom)
		)
	)
	(text "RPI_ID_SC"
		(exclude_from_sim no)
		(at 138.43 120.65 0)
		(effects
			(font
				(size 1.27 1.27)
			)
			(justify right bottom)
		)
	)
	(text "UART0_RX/RPI_GPIO15"
		(exclude_from_sim no)
		(at 162.56 142.24 0)
		(effects
			(font
				(size 1.27 1.27)
			)
			(justify right bottom)
		)
	)
	(text "RPI_GPIO24"
		(exclude_from_sim no)
		(at 162.56 134.62 0)
		(effects
			(font
				(size 1.27 1.27)
			)
			(justify right bottom)
		)
	)
	(text "GND\n"
		(exclude_from_sim no)
		(at 165.1 132.08 0)
		(effects
			(font
				(size 1.27 1.27)
			)
			(justify right bottom)
		)
	)
	(text "GLOBAL_EN"
		(exclude_from_sim no)
		(at 176.53 203.2 0)
		(effects
			(font
				(size 1.27 1.27)
			)
			(justify right bottom)
		)
	)
	(text "RPI_GPIO07"
		(exclude_from_sim no)
		(at 162.56 124.46 0)
		(effects
			(font
				(size 1.27 1.27)
			)
			(justify right bottom)
		)
	)
	(text "SD_DAT4\n"
		(exclude_from_sim no)
		(at 280.67 161.29 0)
		(effects
			(font
				(size 1.27 1.27)
			)
			(justify left bottom)
		)
	)
	(text "Ethernet_Pair0_P"
		(exclude_from_sim no)
		(at 238.125 90.17 0)
		(effects
			(font
				(size 1.27 1.27)
			)
			(justify left bottom)
		)
	)
	(text "SD_DAT0"
		(exclude_from_sim no)
		(at 127.635 156.21 0)
		(effects
			(font
				(size 1.27 1.27)
			)
			(justify right bottom)
		)
	)
	(text "UART5_TX/RPI_GPIO12"
		(exclude_from_sim no)
		(at 163.83 116.84 0)
		(effects
			(font
				(size 1.27 1.27)
			)
			(justify right bottom)
		)
	)
	(text "SD_DAT1"
		(exclude_from_sim no)
		(at 127.635 161.29 0)
		(effects
			(font
				(size 1.27 1.27)
			)
			(justify right bottom)
		)
	)
	(text "Ethernet_Pair2_P"
		(exclude_from_sim no)
		(at 177.8 89.535 0)
		(effects
			(font
				(size 1.27 1.27)
			)
			(justify right bottom)
		)
	)
	(text "nEXTRST"
		(exclude_from_sim no)
		(at 223.52 203.2 0)
		(effects
			(font
				(size 1.27 1.27)
			)
			(justify left bottom)
		)
	)
	(text "SDA1/RPI_GPIO02"
		(exclude_from_sim no)
		(at 254 149.86 0)
		(effects
			(font
				(size 1.27 1.27)
			)
			(justify left bottom)
		)
	)
	(text "RPI_GPIO17"
		(exclude_from_sim no)
		(at 285.115 139.7 0)
		(effects
			(font
				(size 1.27 1.27)
			)
			(justify left bottom)
		)
	)
	(text "RPI_GPIO11"
		(exclude_from_sim no)
		(at 254 124.46 0)
		(effects
			(font
				(size 1.27 1.27)
			)
			(justify left bottom)
		)
	)
	(text "Ethernet_nLED2"
		(exclude_from_sim no)
		(at 177.8 97.155 0)
		(effects
			(font
				(size 1.27 1.27)
			)
			(justify right bottom)
		)
	)
	(text "PI_LED_nPWR"
		(exclude_from_sim no)
		(at 176.53 198.12 0)
		(effects
			(font
				(size 1.27 1.27)
			)
			(justify right bottom)
		)
	)
	(text "SD_VDD_OVERRIDE"
		(exclude_from_sim no)
		(at 167.64 170.18 0)
		(effects
			(font
				(size 1.27 1.27)
			)
			(justify right bottom)
		)
	)
	(text "SD_DAT6"
		(exclude_from_sim no)
		(at 280.67 166.37 0)
		(effects
			(font
				(size 1.27 1.27)
			)
			(justify left bottom)
		)
	)
	(text "SPI6_MISO/RPI_GPIO19"
		(exclude_from_sim no)
		(at 254 109.22 0)
		(effects
			(font
				(size 1.27 1.27)
			)
			(justify left bottom)
		)
	)
	(text "UART4_TX/RPI_GPIO08"
		(exclude_from_sim no)
		(at 162.56 127 0)
		(effects
			(font
				(size 1.27 1.27)
			)
			(justify right bottom)
		)
	)
	(text "Ethernet_nLED1"
		(exclude_from_sim no)
		(at 177.8 99.695 0)
		(effects
			(font
				(size 1.27 1.27)
			)
			(justify right bottom)
		)
	)
	(text "SD_DAT7"
		(exclude_from_sim no)
		(at 280.67 163.83 0)
		(effects
			(font
				(size 1.27 1.27)
			)
			(justify left bottom)
		)
	)
	(text "SPI6_SCLK/RPI_GPIO21"
		(exclude_from_sim no)
		(at 163.83 109.22 0)
		(effects
			(font
				(size 1.27 1.27)
			)
			(justify right bottom)
		)
	)
	(text "RPI_GPIO10"
		(exclude_from_sim no)
		(at 254 132.08 0)
		(effects
			(font
				(size 1.27 1.27)
			)
			(justify left bottom)
		)
	)
	(text "Ethernet_Pair1_N"
		(exclude_from_sim no)
		(at 238.125 82.55 0)
		(effects
			(font
				(size 1.27 1.27)
			)
			(justify left bottom)
		)
	)
	(text "SD_CLK"
		(exclude_from_sim no)
		(at 127.635 148.59 0)
		(effects
			(font
				(size 1.27 1.27)
			)
			(justify right bottom)
		)
	)
	(text "RUN_PG"
		(exclude_from_sim no)
		(at 222.25 193.04 0)
		(effects
			(font
				(size 1.27 1.27)
			)
			(justify left bottom)
		)
	)
	(text "UART0_TX/RPI_GPIO14"
		(exclude_from_sim no)
		(at 162.56 147.32 0)
		(effects
			(font
				(size 1.27 1.27)
			)
			(justify right bottom)
		)
	)
	(text "SD_CMD\n"
		(exclude_from_sim no)
		(at 280.67 153.67 0)
		(effects
			(font
				(size 1.27 1.27)
			)
			(justify left bottom)
		)
	)
	(text "SDA6/RPI_GPIO22"
		(exclude_from_sim no)
		(at 254 134.62 0)
		(effects
			(font
				(size 1.27 1.27)
			)
			(justify left bottom)
		)
	)
	(text "SD_PWR_ON"
		(exclude_from_sim no)
		(at 172.72 172.72 0)
		(effects
			(font
				(size 1.27 1.27)
			)
			(justify right bottom)
		)
	)
	(text "Ethernet_Pair1_P"
		(exclude_from_sim no)
		(at 238.125 80.01 0)
		(effects
			(font
				(size 1.27 1.27)
			)
			(justify left bottom)
		)
	)
	(text "Ethernet_Pair3_N"
		(exclude_from_sim no)
		(at 177.8 81.915 0)
		(effects
			(font
				(size 1.27 1.27)
			)
			(justify right bottom)
		)
	)
	(text "AnalogIP0"
		(exclude_from_sim no)
		(at 222.25 198.12 0)
		(effects
			(font
				(size 1.27 1.27)
			)
			(justify left bottom)
		)
	)
	(text "Ethernet_Pair2_N"
		(exclude_from_sim no)
		(at 177.8 86.995 0)
		(effects
			(font
				(size 1.27 1.27)
			)
			(justify right bottom)
		)
	)
	(text "Camera_GPIO"
		(exclude_from_sim no)
		(at 176.53 200.66 0)
		(effects
			(font
				(size 1.27 1.27)
			)
			(justify right bottom)
		)
	)
	(text "RPI_GPIO26"
		(exclude_from_sim no)
		(at 254 106.68 0)
		(effects
			(font
				(size 1.27 1.27)
			)
			(justify left bottom)
		)
	)
	(text "RPI_GPIO16"
		(exclude_from_sim no)
		(at 163.83 114.3 0)
		(effects
			(font
				(size 1.27 1.27)
			)
			(justify right bottom)
		)
	)
	(text "SCL1/RPI_GPIO03"
		(exclude_from_sim no)
		(at 254 147.32 0)
		(effects
			(font
				(size 1.27 1.27)
			)
			(justify left bottom)
		)
	)
	(text "SD_DAT3"
		(exclude_from_sim no)
		(at 127.635 153.67 0)
		(effects
			(font
				(size 1.27 1.27)
			)
			(justify right bottom)
		)
	)
	(text "reserved"
		(exclude_from_sim no)
		(at 241.3 172.72 0)
		(effects
			(font
				(size 1.27 1.27)
			)
			(justify left bottom)
		)
	)
	(text "UART3_RX/RPI_GPIO05"
		(exclude_from_sim no)
		(at 254 119.38 0)
		(effects
			(font
				(size 1.27 1.27)
			)
			(justify left bottom)
		)
	)
	(text "Ethernet_nLED3"
		(exclude_from_sim no)
		(at 177.8 94.615 0)
		(effects
			(font
				(size 1.27 1.27)
			)
			(justify right bottom)
		)
	)
	(text "UART3_TX/RPI_GPIO04"
		(exclude_from_sim no)
		(at 254 144.78 0)
		(effects
			(font
				(size 1.27 1.27)
			)
			(justify left bottom)
		)
	)
	(text "RPI_GPIO27"
		(exclude_from_sim no)
		(at 239.395 137.16 0)
		(effects
			(font
				(size 1.27 1.27)
			)
			(justify left bottom)
		)
	)
	(text "nRPIBOOT"
		(exclude_from_sim no)
		(at 176.53 195.58 0)
		(effects
			(font
				(size 1.27 1.27)
			)
			(justify right bottom)
		)
	)
	(text "SPI6_CEO_N/RPI_GPIO18"
		(exclude_from_sim no)
		(at 162.56 139.7 0)
		(effects
			(font
				(size 1.27 1.27)
			)
			(justify right bottom)
		)
	)
	(text "SCL6/RPI_GPIO23"
		(exclude_from_sim no)
		(at 162.56 137.16 0)
		(effects
			(font
				(size 1.27 1.27)
			)
			(justify right bottom)
		)
	)
	(text "UART4_RX/RPI_GPIO09"
		(exclude_from_sim no)
		(at 254 127 0)
		(effects
			(font
				(size 1.27 1.27)
			)
			(justify left bottom)
		)
	)
	(text "EEPROM_nWP"
		(exclude_from_sim no)
		(at 238.125 100.33 0)
		(effects
			(font
				(size 1.27 1.27)
			)
			(justify left bottom)
		)
	)
	(text "nLED_ACT"
		(exclude_from_sim no)
		(at 177.8 102.235 0)
		(effects
			(font
				(size 1.27 1.27)
			)
			(justify right bottom)
		)
	)
	(text "SD_DAT2"
		(exclude_from_sim no)
		(at 127.635 163.83 0)
		(effects
			(font
				(size 1.27 1.27)
			)
			(justify right bottom)
		)
	)
	(junction
		(at 218.44 128.27)
		(diameter 0)
		(color 0 0 0 0)
	)
	(junction
		(at 196.85 179.07)
		(diameter 0)
		(color 0 0 0 0)
	)
	(junction
		(at 199.39 105.41)
		(diameter 0)
		(color 0 0 0 0)
	)
	(junction
		(at 218.44 92.71)
		(diameter 0)
		(color 0 0 0 0)
	)
	(junction
		(at 218.44 151.13)
		(diameter 0)
		(color 0 0 0 0)
	)
	(junction
		(at 218.44 168.91)
		(diameter 0)
		(color 0 0 0 0)
	)
	(junction
		(at 199.39 92.71)
		(diameter 0)
		(color 0 0 0 0)
	)
	(junction
		(at 220.98 182.88)
		(diameter 0)
		(color 0 0 0 0)
	)
	(junction
		(at 196.85 181.61)
		(diameter 0)
		(color 0 0 0 0)
	)
	(junction
		(at 199.39 143.51)
		(diameter 0)
		(color 0 0 0 0)
	)
	(junction
		(at 199.39 85.09)
		(diameter 0)
		(color 0 0 0 0)
	)
	(junction
		(at 255.27 138.43)
		(diameter 0)
		(color 0 0 0 0)
	)
	(junction
		(at 196.85 180.34)
		(diameter 0)
		(color 0 0 0 0)
	)
	(junction
		(at 199.39 166.37)
		(diameter 0)
		(color 0 0 0 0)
	)
	(junction
		(at 199.39 118.11)
		(diameter 0)
		(color 0 0 0 0)
	)
	(junction
		(at 196.85 176.53)
		(diameter 0)
		(color 0 0 0 0)
	)
	(junction
		(at 218.44 140.97)
		(diameter 0)
		(color 0 0 0 0)
	)
	(junction
		(at 139.7 196.85)
		(diameter 0)
		(color 0 0 0 0)
	)
	(junction
		(at 199.39 151.13)
		(diameter 0)
		(color 0 0 0 0)
	)
	(junction
		(at 218.44 158.75)
		(diameter 0)
		(color 0 0 0 0)
	)
	(junction
		(at 218.44 102.87)
		(diameter 0)
		(color 0 0 0 0)
	)
	(junction
		(at 218.44 204.47)
		(diameter 0)
		(color 0 0 0 0)
	)
	(junction
		(at 218.44 115.57)
		(diameter 0)
		(color 0 0 0 0)
	)
	(junction
		(at 196.85 184.15)
		(diameter 0)
		(color 0 0 0 0)
	)
	(junction
		(at 218.44 85.09)
		(diameter 0)
		(color 0 0 0 0)
	)
	(junction
		(at 218.44 199.39)
		(diameter 0)
		(color 0 0 0 0)
	)
	(junction
		(at 220.98 187.96)
		(diameter 0)
		(color 0 0 0 0)
	)
	(junction
		(at 199.39 158.75)
		(diameter 0)
		(color 0 0 0 0)
	)
	(no_connect
		(at 215.9 194.31)
	)
	(no_connect
		(at 201.93 199.39)
	)
	(no_connect
		(at 196.85 102.87)
	)
	(no_connect
		(at 215.9 171.45)
	)
	(no_connect
		(at 196.85 100.33)
	)
	(no_connect
		(at 215.9 201.93)
	)
	(no_connect
		(at 220.98 100.33)
	)
	(no_connect
		(at 201.93 194.31)
	)
	(no_connect
		(at 215.9 196.85)
	)
	(no_connect
		(at 215.9 191.77)
	)
	(bus_entry
		(at 236.22 95.25)
		(size -2.54 2.54)
		(stroke
			(width 0)
			(type default)
		)
	)
	(bus_entry
		(at 236.22 92.71)
		(size -2.54 2.54)
		(stroke
			(width 0)
			(type default)
		)
	)
	(bus_entry
		(at 179.07 80.01)
		(size 2.54 2.54)
		(stroke
			(width 0)
			(type default)
		)
	)
	(bus_entry
		(at 236.22 77.47)
		(size -2.54 2.54)
		(stroke
			(width 0)
			(type default)
		)
	)
	(bus_entry
		(at 129.54 161.29)
		(size 2.54 2.54)
		(stroke
			(width 0)
			(type default)
		)
	)
	(bus_entry
		(at 279.4 176.53)
		(size -2.54 2.54)
		(stroke
			(width 0)
			(type default)
		)
	)
	(bus_entry
		(at 179.07 85.09)
		(size 2.54 2.54)
		(stroke
			(width 0)
			(type default)
		)
	)
	(bus_entry
		(at 129.54 146.05)
		(size 2.54 2.54)
		(stroke
			(width 0)
			(type default)
		)
	)
	(bus_entry
		(at 139.7 118.11)
		(size 2.54 2.54)
		(stroke
			(width 0)
			(type default)
		)
	)
	(bus_entry
		(at 285.75 118.11)
		(size -2.54 2.54)
		(stroke
			(width 0)
			(type default)
		)
	)
	(bus_entry
		(at 129.54 158.75)
		(size 2.54 2.54)
		(stroke
			(width 0)
			(type default)
		)
	)
	(bus_entry
		(at 279.4 163.83)
		(size -2.54 2.54)
		(stroke
			(width 0)
			(type default)
		)
	)
	(bus_entry
		(at 236.22 80.01)
		(size -2.54 2.54)
		(stroke
			(width 0)
			(type default)
		)
	)
	(bus_entry
		(at 179.07 87.63)
		(size 2.54 2.54)
		(stroke
			(width 0)
			(type default)
		)
	)
	(bus_entry
		(at 279.4 158.75)
		(size -2.54 2.54)
		(stroke
			(width 0)
			(type default)
		)
	)
	(bus_entry
		(at 129.54 151.13)
		(size 2.54 2.54)
		(stroke
			(width 0)
			(type default)
		)
	)
	(bus_entry
		(at 179.07 77.47)
		(size 2.54 2.54)
		(stroke
			(width 0)
			(type default)
		)
	)
	(bus_entry
		(at 279.4 151.13)
		(size -2.54 2.54)
		(stroke
			(width 0)
			(type default)
		)
	)
	(bus_entry
		(at 236.22 85.09)
		(size -2.54 2.54)
		(stroke
			(width 0)
			(type default)
		)
	)
	(bus_entry
		(at 279.4 153.67)
		(size -2.54 2.54)
		(stroke
			(width 0)
			(type default)
		)
	)
	(bus_entry
		(at 179.07 95.25)
		(size 2.54 2.54)
		(stroke
			(width 0)
			(type default)
		)
	)
	(bus_entry
		(at 179.07 92.71)
		(size 2.54 2.54)
		(stroke
			(width 0)
			(type default)
		)
	)
	(bus_entry
		(at 129.54 153.67)
		(size 2.54 2.54)
		(stroke
			(width 0)
			(type default)
		)
	)
	(bus_entry
		(at 279.4 161.29)
		(size -2.54 2.54)
		(stroke
			(width 0)
			(type default)
		)
	)
	(bus_entry
		(at 236.22 87.63)
		(size -2.54 2.54)
		(stroke
			(width 0)
			(type default)
		)
	)
	(bus_entry
		(at 279.4 173.99)
		(size -2.54 2.54)
		(stroke
			(width 0)
			(type default)
		)
	)
	(bus
		(pts
			(xy 179.07 92.71) (xy 179.07 95.25)
		)
		(stroke
			(width 0)
			(type default)
		)
	)
	(wire
		(pts
			(xy 175.26 130.81) (xy 179.07 130.81)
		)
		(stroke
			(width 0)
			(type default)
		)
	)
	(wire
		(pts
			(xy 181.61 82.55) (xy 201.93 82.55)
		)
		(stroke
			(width 0)
			(type default)
		)
	)
	(wire
		(pts
			(xy 196.85 173.99) (xy 201.93 173.99)
		)
		(stroke
			(width 0)
			(type default)
		)
	)
	(wire
		(pts
			(xy 132.08 148.59) (xy 201.93 148.59)
		)
		(stroke
			(width 0)
			(type default)
		)
	)
	(wire
		(pts
			(xy 218.44 204.47) (xy 218.44 208.28)
		)
		(stroke
			(width 0)
			(type default)
		)
	)
	(bus
		(pts
			(xy 280.67 148.59) (xy 281.94 148.59)
		)
		(stroke
			(width 0)
			(type default)
		)
	)
	(wire
		(pts
			(xy 220.98 187.96) (xy 220.98 189.23)
		)
		(stroke
			(width 0)
			(type default)
		)
	)
	(wire
		(pts
			(xy 220.98 182.88) (xy 220.98 184.15)
		)
		(stroke
			(width 0)
			(type default)
		)
	)
	(wire
		(pts
			(xy 139.7 195.58) (xy 139.7 196.85)
		)
		(stroke
			(width 0)
			(type default)
		)
	)
	(wire
		(pts
			(xy 220.98 181.61) (xy 220.98 182.88)
		)
		(stroke
			(width 0)
			(type default)
		)
	)
	(wire
		(pts
			(xy 218.44 140.97) (xy 218.44 151.13)
		)
		(stroke
			(width 0)
			(type default)
		)
	)
	(bus
		(pts
			(xy 129.54 153.67) (xy 129.54 158.75)
		)
		(stroke
			(width 0)
			(type default)
		)
	)
	(bus
		(pts
			(xy 280.67 148.59) (xy 279.4 149.86)
		)
		(stroke
			(width 0)
			(type default)
		)
	)
	(wire
		(pts
			(xy 215.9 87.63) (xy 233.68 87.63)
		)
		(stroke
			(width 0)
			(type default)
		)
	)
	(wire
		(pts
			(xy 215.9 166.37) (xy 276.86 166.37)
		)
		(stroke
			(width 0)
			(type default)
		)
	)
	(bus
		(pts
			(xy 281.94 171.45) (xy 280.67 171.45)
		)
		(stroke
			(width 0)
			(type default)
		)
	)
	(wire
		(pts
			(xy 215.9 100.33) (xy 220.98 100.33)
		)
		(stroke
			(width 0)
			(type default)
		)
	)
	(bus
		(pts
			(xy 279.4 153.67) (xy 279.4 158.75)
		)
		(stroke
			(width 0)
			(type default)
		)
	)
	(bus
		(pts
			(xy 236.22 80.01) (xy 236.22 85.09)
		)
		(stroke
			(width 0)
			(type default)
		)
	)
	(bus
		(pts
			(xy 288.29 115.57) (xy 287.02 115.57)
		)
		(stroke
			(width 0)
			(type default)
		)
	)
	(wire
		(pts
			(xy 220.98 182.88) (xy 223.52 182.88)
		)
		(stroke
			(width 0)
			(type default)
		)
	)
	(wire
		(pts
			(xy 196.85 201.93) (xy 201.93 201.93)
		)
		(stroke
			(width 0)
			(type default)
		)
	)
	(wire
		(pts
			(xy 196.85 135.89) (xy 201.93 135.89)
		)
		(stroke
			(width 0)
			(type default)
		)
	)
	(bus
		(pts
			(xy 236.22 76.2) (xy 236.22 77.47)
		)
		(stroke
			(width 0)
			(type default)
		)
	)
	(wire
		(pts
			(xy 196.85 138.43) (xy 201.93 138.43)
		)
		(stroke
			(width 0)
			(type default)
		)
	)
	(wire
		(pts
			(xy 215.9 115.57) (xy 218.44 115.57)
		)
		(stroke
			(width 0)
			(type default)
		)
	)
	(wire
		(pts
			(xy 218.44 158.75) (xy 218.44 168.91)
		)
		(stroke
			(width 0)
			(type default)
		)
	)
	(wire
		(pts
			(xy 196.85 184.15) (xy 201.93 184.15)
		)
		(stroke
			(width 0)
			(type default)
		)
	)
	(bus
		(pts
			(xy 177.8 74.93) (xy 176.53 74.93)
		)
		(stroke
			(width 0)
			(type default)
		)
	)
	(wire
		(pts
			(xy 196.85 186.69) (xy 201.93 186.69)
		)
		(stroke
			(width 0)
			(type default)
		)
	)
	(wire
		(pts
			(xy 199.39 118.11) (xy 199.39 143.51)
		)
		(stroke
			(width 0)
			(type default)
		)
	)
	(wire
		(pts
			(xy 132.08 161.29) (xy 201.93 161.29)
		)
		(stroke
			(width 0)
			(type default)
		)
	)
	(wire
		(pts
			(xy 132.08 153.67) (xy 201.93 153.67)
		)
		(stroke
			(width 0)
			(type default)
		)
	)
	(wire
		(pts
			(xy 139.7 208.28) (xy 139.7 210.82)
		)
		(stroke
			(width 0)
			(type default)
		)
	)
	(bus
		(pts
			(xy 179.07 80.01) (xy 179.07 85.09)
		)
		(stroke
			(width 0)
			(type default)
		)
	)
	(wire
		(pts
			(xy 218.44 168.91) (xy 218.44 199.39)
		)
		(stroke
			(width 0)
			(type default)
		)
	)
	(wire
		(pts
			(xy 196.85 179.07) (xy 201.93 179.07)
		)
		(stroke
			(width 0)
			(type default)
		)
	)
	(wire
		(pts
			(xy 196.85 128.27) (xy 201.93 128.27)
		)
		(stroke
			(width 0)
			(type default)
		)
	)
	(wire
		(pts
			(xy 199.39 151.13) (xy 199.39 158.75)
		)
		(stroke
			(width 0)
			(type default)
		)
	)
	(wire
		(pts
			(xy 218.44 92.71) (xy 218.44 102.87)
		)
		(stroke
			(width 0)
			(type default)
		)
	)
	(wire
		(pts
			(xy 196.85 181.61) (xy 196.85 184.15)
		)
		(stroke
			(width 0)
			(type default)
		)
	)
	(wire
		(pts
			(xy 215.9 97.79) (xy 233.68 97.79)
		)
		(stroke
			(width 0)
			(type default)
		)
	)
	(wire
		(pts
			(xy 215.9 186.69) (xy 220.98 186.69)
		)
		(stroke
			(width 0)
			(type default)
		)
	)
	(bus
		(pts
			(xy 128.27 143.51) (xy 129.54 144.78)
		)
		(stroke
			(width 0)
			(type default)
		)
	)
	(wire
		(pts
			(xy 215.9 168.91) (xy 218.44 168.91)
		)
		(stroke
			(width 0)
			(type default)
		)
	)
	(wire
		(pts
			(xy 196.85 176.53) (xy 201.93 176.53)
		)
		(stroke
			(width 0)
			(type default)
		)
	)
	(wire
		(pts
			(xy 215.9 102.87) (xy 218.44 102.87)
		)
		(stroke
			(width 0)
			(type default)
		)
	)
	(wire
		(pts
			(xy 266.7 137.16) (xy 261.62 137.16)
		)
		(stroke
			(width 0)
			(type default)
		)
	)
	(wire
		(pts
			(xy 127 204.47) (xy 127 205.74)
		)
		(stroke
			(width 0)
			(type default)
		)
	)
	(wire
		(pts
			(xy 196.85 191.77) (xy 201.93 191.77)
		)
		(stroke
			(width 0)
			(type default)
		)
	)
	(wire
		(pts
			(xy 181.61 90.17) (xy 201.93 90.17)
		)
		(stroke
			(width 0)
			(type default)
		)
	)
	(wire
		(pts
			(xy 199.39 158.75) (xy 201.93 158.75)
		)
		(stroke
			(width 0)
			(type default)
		)
	)
	(wire
		(pts
			(xy 215.9 161.29) (xy 276.86 161.29)
		)
		(stroke
			(width 0)
			(type default)
		)
	)
	(bus
		(pts
			(xy 179.07 76.2) (xy 179.07 77.47)
		)
		(stroke
			(width 0)
			(type default)
		)
	)
	(wire
		(pts
			(xy 199.39 158.75) (xy 199.39 166.37)
		)
		(stroke
			(width 0)
			(type default)
		)
	)
	(wire
		(pts
			(xy 196.85 146.05) (xy 201.93 146.05)
		)
		(stroke
			(width 0)
			(type default)
		)
	)
	(wire
		(pts
			(xy 199.39 166.37) (xy 199.39 208.28)
		)
		(stroke
			(width 0)
			(type default)
		)
	)
	(wire
		(pts
			(xy 196.85 100.33) (xy 201.93 100.33)
		)
		(stroke
			(width 0)
			(type default)
		)
	)
	(wire
		(pts
			(xy 196.85 110.49) (xy 201.93 110.49)
		)
		(stroke
			(width 0)
			(type default)
		)
	)
	(wire
		(pts
			(xy 196.85 102.87) (xy 201.93 102.87)
		)
		(stroke
			(width 0)
			(type default)
		)
	)
	(wire
		(pts
			(xy 215.9 105.41) (xy 220.98 105.41)
		)
		(stroke
			(width 0)
			(type default)
		)
	)
	(wire
		(pts
			(xy 215.9 148.59) (xy 220.98 148.59)
		)
		(stroke
			(width 0)
			(type default)
		)
	)
	(wire
		(pts
			(xy 218.44 102.87) (xy 218.44 115.57)
		)
		(stroke
			(width 0)
			(type default)
		)
	)
	(wire
		(pts
			(xy 215.9 133.35) (xy 220.98 133.35)
		)
		(stroke
			(width 0)
			(type default)
		)
	)
	(wire
		(pts
			(xy 139.7 196.85) (xy 139.7 198.12)
		)
		(stroke
			(width 0)
			(type default)
		)
	)
	(wire
		(pts
			(xy 218.44 77.47) (xy 218.44 85.09)
		)
		(stroke
			(width 0)
			(type default)
		)
	)
	(wire
		(pts
			(xy 196.85 123.19) (xy 201.93 123.19)
		)
		(stroke
			(width 0)
			(type default)
		)
	)
	(wire
		(pts
			(xy 215.9 120.65) (xy 283.21 120.65)
		)
		(stroke
			(width 0)
			(type default)
		)
	)
	(wire
		(pts
			(xy 215.9 118.11) (xy 220.98 118.11)
		)
		(stroke
			(width 0)
			(type default)
		)
	)
	(wire
		(pts
			(xy 194.31 180.34) (xy 196.85 180.34)
		)
		(stroke
			(width 0)
			(type default)
		)
	)
	(wire
		(pts
			(xy 199.39 166.37) (xy 201.93 166.37)
		)
		(stroke
			(width 0)
			(type default)
		)
	)
	(wire
		(pts
			(xy 196.85 176.53) (xy 196.85 179.07)
		)
		(stroke
			(width 0)
			(type default)
		)
	)
	(wire
		(pts
			(xy 215.9 77.47) (xy 218.44 77.47)
		)
		(stroke
			(width 0)
			(type default)
		)
	)
	(wire
		(pts
			(xy 199.39 85.09) (xy 201.93 85.09)
		)
		(stroke
			(width 0)
			(type default)
		)
	)
	(wire
		(pts
			(xy 215.9 110.49) (xy 220.98 110.49)
		)
		(stroke
			(width 0)
			(type default)
		)
	)
	(bus
		(pts
			(xy 179.07 87.63) (xy 179.07 92.71)
		)
		(stroke
			(width 0)
			(type default)
		)
	)
	(wire
		(pts
			(xy 220.98 187.96) (xy 223.52 187.96)
		)
		(stroke
			(width 0)
			(type default)
		)
	)
	(bus
		(pts
			(xy 287.02 115.57) (xy 285.75 116.84)
		)
		(stroke
			(width 0)
			(type default)
		)
	)
	(wire
		(pts
			(xy 215.9 113.03) (xy 220.98 113.03)
		)
		(stroke
			(width 0)
			(type default)
		)
	)
	(wire
		(pts
			(xy 196.85 173.99) (xy 196.85 176.53)
		)
		(stroke
			(width 0)
			(type default)
		)
	)
	(wire
		(pts
			(xy 215.9 92.71) (xy 218.44 92.71)
		)
		(stroke
			(width 0)
			(type default)
		)
	)
	(wire
		(pts
			(xy 218.44 151.13) (xy 218.44 158.75)
		)
		(stroke
			(width 0)
			(type default)
		)
	)
	(bus
		(pts
			(xy 279.4 151.13) (xy 279.4 153.67)
		)
		(stroke
			(width 0)
			(type default)
		)
	)
	(wire
		(pts
			(xy 215.9 85.09) (xy 218.44 85.09)
		)
		(stroke
			(width 0)
			(type default)
		)
	)
	(wire
		(pts
			(xy 215.9 181.61) (xy 220.98 181.61)
		)
		(stroke
			(width 0)
			(type default)
		)
	)
	(wire
		(pts
			(xy 132.08 156.21) (xy 201.93 156.21)
		)
		(stroke
			(width 0)
			(type default)
		)
	)
	(wire
		(pts
			(xy 215.9 184.15) (xy 220.98 184.15)
		)
		(stroke
			(width 0)
			(type default)
		)
	)
	(wire
		(pts
			(xy 215.9 125.73) (xy 220.98 125.73)
		)
		(stroke
			(width 0)
			(type default)
		)
	)
	(wire
		(pts
			(xy 215.9 138.43) (xy 255.27 138.43)
		)
		(stroke
			(width 0)
			(type default)
		)
	)
	(wire
		(pts
			(xy 181.61 80.01) (xy 201.93 80.01)
		)
		(stroke
			(width 0)
			(type default)
		)
	)
	(wire
		(pts
			(xy 181.61 87.63) (xy 201.93 87.63)
		)
		(stroke
			(width 0)
			(type default)
		)
	)
	(wire
		(pts
			(xy 184.15 130.81) (xy 201.93 130.81)
		)
		(stroke
			(width 0)
			(type default)
		)
	)
	(wire
		(pts
			(xy 255.27 137.16) (xy 256.54 137.16)
		)
		(stroke
			(width 0)
			(type default)
		)
	)
	(wire
		(pts
			(xy 196.85 115.57) (xy 201.93 115.57)
		)
		(stroke
			(width 0)
			(type default)
		)
	)
	(wire
		(pts
			(xy 218.44 128.27) (xy 218.44 140.97)
		)
		(stroke
			(width 0)
			(type default)
		)
	)
	(wire
		(pts
			(xy 215.9 143.51) (xy 220.98 143.51)
		)
		(stroke
			(width 0)
			(type default)
		)
	)
	(wire
		(pts
			(xy 199.39 105.41) (xy 201.93 105.41)
		)
		(stroke
			(width 0)
			(type default)
		)
	)
	(wire
		(pts
			(xy 199.39 143.51) (xy 201.93 143.51)
		)
		(stroke
			(width 0)
			(type default)
		)
	)
	(wire
		(pts
			(xy 196.85 189.23) (xy 201.93 189.23)
		)
		(stroke
			(width 0)
			(type default)
		)
	)
	(wire
		(pts
			(xy 199.39 85.09) (xy 199.39 92.71)
		)
		(stroke
			(width 0)
			(type default)
		)
	)
	(wire
		(pts
			(xy 199.39 92.71) (xy 201.93 92.71)
		)
		(stroke
			(width 0)
			(type default)
		)
	)
	(wire
		(pts
			(xy 215.9 176.53) (xy 276.86 176.53)
		)
		(stroke
			(width 0)
			(type default)
		)
	)
	(wire
		(pts
			(xy 215.9 107.95) (xy 220.98 107.95)
		)
		(stroke
			(width 0)
			(type default)
		)
	)
	(bus
		(pts
			(xy 237.49 74.93) (xy 238.76 74.93)
		)
		(stroke
			(width 0)
			(type default)
		)
	)
	(wire
		(pts
			(xy 255.27 137.16) (xy 255.27 138.43)
		)
		(stroke
			(width 0)
			(type default)
		)
	)
	(wire
		(pts
			(xy 199.39 105.41) (xy 199.39 118.11)
		)
		(stroke
			(width 0)
			(type default)
		)
	)
	(wire
		(pts
			(xy 215.9 123.19) (xy 220.98 123.19)
		)
		(stroke
			(width 0)
			(type default)
		)
	)
	(wire
		(pts
			(xy 196.85 184.15) (xy 196.85 186.69)
		)
		(stroke
			(width 0)
			(type default)
		)
	)
	(wire
		(pts
			(xy 199.39 92.71) (xy 199.39 105.41)
		)
		(stroke
			(width 0)
			(type default)
		)
	)
	(wire
		(pts
			(xy 181.61 97.79) (xy 201.93 97.79)
		)
		(stroke
			(width 0)
			(type default)
		)
	)
	(bus
		(pts
			(xy 129.54 144.78) (xy 129.54 146.05)
		)
		(stroke
			(width 0)
			(type default)
		)
	)
	(wire
		(pts
			(xy 215.9 146.05) (xy 220.98 146.05)
		)
		(stroke
			(width 0)
			(type default)
		)
	)
	(wire
		(pts
			(xy 215.9 130.81) (xy 220.98 130.81)
		)
		(stroke
			(width 0)
			(type default)
		)
	)
	(bus
		(pts
			(xy 177.8 74.93) (xy 179.07 76.2)
		)
		(stroke
			(width 0)
			(type default)
		)
	)
	(wire
		(pts
			(xy 261.62 139.7) (xy 266.7 139.7)
		)
		(stroke
			(width 0)
			(type default)
		)
	)
	(bus
		(pts
			(xy 236.22 77.47) (xy 236.22 80.01)
		)
		(stroke
			(width 0)
			(type default)
		)
	)
	(wire
		(pts
			(xy 215.9 199.39) (xy 218.44 199.39)
		)
		(stroke
			(width 0)
			(type default)
		)
	)
	(wire
		(pts
			(xy 185.42 196.85) (xy 201.93 196.85)
		)
		(stroke
			(width 0)
			(type default)
		)
	)
	(wire
		(pts
			(xy 139.7 187.96) (xy 139.7 190.5)
		)
		(stroke
			(width 0)
			(type default)
		)
	)
	(wire
		(pts
			(xy 215.9 189.23) (xy 220.98 189.23)
		)
		(stroke
			(width 0)
			(type default)
		)
	)
	(wire
		(pts
			(xy 215.9 158.75) (xy 218.44 158.75)
		)
		(stroke
			(width 0)
			(type default)
		)
	)
	(wire
		(pts
			(xy 218.44 115.57) (xy 218.44 128.27)
		)
		(stroke
			(width 0)
			(type default)
		)
	)
	(wire
		(pts
			(xy 196.85 133.35) (xy 201.93 133.35)
		)
		(stroke
			(width 0)
			(type default)
		)
	)
	(bus
		(pts
			(xy 279.4 149.86) (xy 279.4 151.13)
		)
		(stroke
			(width 0)
			(type default)
		)
	)
	(bus
		(pts
			(xy 127 143.51) (xy 128.27 143.51)
		)
		(stroke
			(width 0)
			(type default)
		)
	)
	(wire
		(pts
			(xy 199.39 77.47) (xy 199.39 85.09)
		)
		(stroke
			(width 0)
			(type default)
		)
	)
	(wire
		(pts
			(xy 255.27 138.43) (xy 255.27 139.7)
		)
		(stroke
			(width 0)
			(type default)
		)
	)
	(bus
		(pts
			(xy 138.43 115.57) (xy 139.7 116.84)
		)
		(stroke
			(width 0)
			(type default)
		)
	)
	(bus
		(pts
			(xy 236.22 92.71) (xy 236.22 95.25)
		)
		(stroke
			(width 0)
			(type default)
		)
	)
	(bus
		(pts
			(xy 279.4 172.72) (xy 279.4 173.99)
		)
		(stroke
			(width 0)
			(type default)
		)
	)
	(wire
		(pts
			(xy 220.98 187.96) (xy 220.98 186.69)
		)
		(stroke
			(width 0)
			(type default)
		)
	)
	(wire
		(pts
			(xy 127 205.74) (xy 133.35 205.74)
		)
		(stroke
			(width 0)
			(type default)
		)
	)
	(wire
		(pts
			(xy 196.85 107.95) (xy 201.93 107.95)
		)
		(stroke
			(width 0)
			(type default)
		)
	)
	(wire
		(pts
			(xy 201.93 77.47) (xy 199.39 77.47)
		)
		(stroke
			(width 0)
			(type default)
		)
	)
	(bus
		(pts
			(xy 179.07 85.09) (xy 179.07 87.63)
		)
		(stroke
			(width 0)
			(type default)
		)
	)
	(wire
		(pts
			(xy 255.27 139.7) (xy 256.54 139.7)
		)
		(stroke
			(width 0)
			(type default)
		)
	)
	(wire
		(pts
			(xy 196.85 179.07) (xy 196.85 180.34)
		)
		(stroke
			(width 0)
			(type default)
		)
	)
	(wire
		(pts
			(xy 215.9 128.27) (xy 218.44 128.27)
		)
		(stroke
			(width 0)
			(type default)
		)
	)
	(bus
		(pts
			(xy 139.7 116.84) (xy 139.7 118.11)
		)
		(stroke
			(width 0)
			(type default)
		)
	)
	(wire
		(pts
			(xy 196.85 125.73) (xy 201.93 125.73)
		)
		(stroke
			(width 0)
			(type default)
		)
	)
	(wire
		(pts
			(xy 181.61 95.25) (xy 201.93 95.25)
		)
		(stroke
			(width 0)
			(type default)
		)
	)
	(wire
		(pts
			(xy 196.85 181.61) (xy 201.93 181.61)
		)
		(stroke
			(width 0)
			(type default)
		)
	)
	(wire
		(pts
			(xy 139.7 196.85) (xy 162.56 196.85)
		)
		(stroke
			(width 0)
			(type default)
		)
	)
	(bus
		(pts
			(xy 279.4 173.99) (xy 279.4 176.53)
		)
		(stroke
			(width 0)
			(type default)
		)
	)
	(wire
		(pts
			(xy 215.9 151.13) (xy 218.44 151.13)
		)
		(stroke
			(width 0)
			(type default)
		)
	)
	(wire
		(pts
			(xy 196.85 140.97) (xy 201.93 140.97)
		)
		(stroke
			(width 0)
			(type default)
		)
	)
	(wire
		(pts
			(xy 215.9 153.67) (xy 276.86 153.67)
		)
		(stroke
			(width 0)
			(type default)
		)
	)
	(wire
		(pts
			(xy 215.9 204.47) (xy 218.44 204.47)
		)
		(stroke
			(width 0)
			(type default)
		)
	)
	(wire
		(pts
			(xy 199.39 143.51) (xy 199.39 151.13)
		)
		(stroke
			(width 0)
			(type default)
		)
	)
	(bus
		(pts
			(xy 280.67 171.45) (xy 279.4 172.72)
		)
		(stroke
			(width 0)
			(type default)
		)
	)
	(wire
		(pts
			(xy 215.9 90.17) (xy 233.68 90.17)
		)
		(stroke
			(width 0)
			(type default)
		)
	)
	(wire
		(pts
			(xy 215.9 163.83) (xy 276.86 163.83)
		)
		(stroke
			(width 0)
			(type default)
		)
	)
	(bus
		(pts
			(xy 179.07 77.47) (xy 179.07 80.01)
		)
		(stroke
			(width 0)
			(type default)
		)
	)
	(bus
		(pts
			(xy 279.4 158.75) (xy 279.4 161.29)
		)
		(stroke
			(width 0)
			(type default)
		)
	)
	(bus
		(pts
			(xy 279.4 161.29) (xy 279.4 163.83)
		)
		(stroke
			(width 0)
			(type default)
		)
	)
	(wire
		(pts
			(xy 196.85 168.91) (xy 201.93 168.91)
		)
		(stroke
			(width 0)
			(type default)
		)
	)
	(wire
		(pts
			(xy 215.9 173.99) (xy 220.98 173.99)
		)
		(stroke
			(width 0)
			(type default)
		)
	)
	(wire
		(pts
			(xy 218.44 199.39) (xy 218.44 204.47)
		)
		(stroke
			(width 0)
			(type default)
		)
	)
	(wire
		(pts
			(xy 215.9 179.07) (xy 276.86 179.07)
		)
		(stroke
			(width 0)
			(type default)
		)
	)
	(wire
		(pts
			(xy 215.9 80.01) (xy 233.68 80.01)
		)
		(stroke
			(width 0)
			(type default)
		)
	)
	(wire
		(pts
			(xy 199.39 118.11) (xy 201.93 118.11)
		)
		(stroke
			(width 0)
			(type default)
		)
	)
	(bus
		(pts
			(xy 129.54 158.75) (xy 129.54 161.29)
		)
		(stroke
			(width 0)
			(type default)
		)
	)
	(bus
		(pts
			(xy 137.16 115.57) (xy 138.43 115.57)
		)
		(stroke
			(width 0)
			(type default)
		)
	)
	(bus
		(pts
			(xy 236.22 85.09) (xy 236.22 87.63)
		)
		(stroke
			(width 0)
			(type default)
		)
	)
	(wire
		(pts
			(xy 215.9 95.25) (xy 233.68 95.25)
		)
		(stroke
			(width 0)
			(type default)
		)
	)
	(wire
		(pts
			(xy 199.39 151.13) (xy 201.93 151.13)
		)
		(stroke
			(width 0)
			(type default)
		)
	)
	(wire
		(pts
			(xy 215.9 135.89) (xy 220.98 135.89)
		)
		(stroke
			(width 0)
			(type default)
		)
	)
	(wire
		(pts
			(xy 196.85 113.03) (xy 201.93 113.03)
		)
		(stroke
			(width 0)
			(type default)
		)
	)
	(wire
		(pts
			(xy 196.85 180.34) (xy 196.85 181.61)
		)
		(stroke
			(width 0)
			(type default)
		)
	)
	(bus
		(pts
			(xy 129.54 146.05) (xy 129.54 151.13)
		)
		(stroke
			(width 0)
			(type default)
		)
	)
	(wire
		(pts
			(xy 196.85 171.45) (xy 201.93 171.45)
		)
		(stroke
			(width 0)
			(type default)
		)
	)
	(bus
		(pts
			(xy 236.22 87.63) (xy 236.22 92.71)
		)
		(stroke
			(width 0)
			(type default)
		)
	)
	(wire
		(pts
			(xy 132.08 163.83) (xy 201.93 163.83)
		)
		(stroke
			(width 0)
			(type default)
		)
	)
	(bus
		(pts
			(xy 285.75 116.84) (xy 285.75 118.11)
		)
		(stroke
			(width 0)
			(type default)
		)
	)
	(wire
		(pts
			(xy 215.9 140.97) (xy 218.44 140.97)
		)
		(stroke
			(width 0)
			(type default)
		)
	)
	(bus
		(pts
			(xy 237.49 74.93) (xy 236.22 76.2)
		)
		(stroke
			(width 0)
			(type default)
		)
	)
	(wire
		(pts
			(xy 215.9 156.21) (xy 276.86 156.21)
		)
		(stroke
			(width 0)
			(type default)
		)
	)
	(wire
		(pts
			(xy 218.44 85.09) (xy 218.44 92.71)
		)
		(stroke
			(width 0)
			(type default)
		)
	)
	(wire
		(pts
			(xy 142.24 120.65) (xy 201.93 120.65)
		)
		(stroke
			(width 0)
			(type default)
		)
	)
	(wire
		(pts
			(xy 215.9 82.55) (xy 233.68 82.55)
		)
		(stroke
			(width 0)
			(type default)
		)
	)
	(bus
		(pts
			(xy 129.54 151.13) (xy 129.54 153.67)
		)
		(stroke
			(width 0)
			(type default)
		)
	)
	(label "SD.DAT7"
		(at 275.717 163.83 180)
		(effects
			(font
				(size 1.27 1.27)
			)
			(justify right bottom)
		)
	)
	(label "SD.DAT6"
		(at 275.717 166.37 180)
		(effects
			(font
				(size 1.27 1.27)
			)
			(justify right bottom)
		)
	)
	(label "ETH.SYNC_IN"
		(at 233.68 95.25 180)
		(effects
			(font
				(size 1.27 1.27)
			)
			(justify right bottom)
		)
	)
	(label "I^{2}C0.SCL"
		(at 276.225 176.53 180)
		(effects
			(font
				(size 1.27 1.27)
			)
			(justify right bottom)
		)
	)
	(label "ETH.TXRX_B_N"
		(at 233.68 82.55 180)
		(effects
			(font
				(size 1.27 1.27)
			)
			(justify right bottom)
		)
	)
	(label "ETH.TXRX_C_P"
		(at 181.61 90.17 0)
		(effects
			(font
				(size 1.27 1.27)
			)
			(justify left bottom)
		)
	)
	(label "SD.DAT5"
		(at 275.717 156.21 180)
		(effects
			(font
				(size 1.27 1.27)
			)
			(justify right bottom)
		)
	)
	(label "ETH.TXRX_C_N"
		(at 181.61 87.63 0)
		(effects
			(font
				(size 1.27 1.27)
			)
			(justify left bottom)
		)
	)
	(label "ETH.SYNC_OUT"
		(at 233.68 97.79 180)
		(effects
			(font
				(size 1.27 1.27)
			)
			(justify right bottom)
		)
	)
	(label "ETH.LED2"
		(at 181.61 95.25 0)
		(effects
			(font
				(size 1.27 1.27)
			)
			(justify left bottom)
		)
	)
	(label "SD.CLK"
		(at 133.35 148.59 0)
		(effects
			(font
				(size 1.27 1.27)
			)
			(justify left bottom)
		)
	)
	(label "SD.DAT0"
		(at 133.35 156.21 0)
		(effects
			(font
				(size 1.27 1.27)
			)
			(justify left bottom)
		)
	)
	(label "ETH.TXRX_D_N"
		(at 181.61 82.55 0)
		(effects
			(font
				(size 1.27 1.27)
			)
			(justify left bottom)
		)
	)
	(label "ID.SCL"
		(at 142.24 120.65 0)
		(effects
			(font
				(size 1.27 1.27)
			)
			(justify left bottom)
		)
	)
	(label "PI_LED_nPWR"
		(at 162.56 196.85 180)
		(effects
			(font
				(size 1.27 1.27)
			)
			(justify right bottom)
		)
	)
	(label "PI_LED_nPWR"
		(at 185.42 196.85 0)
		(effects
			(font
				(size 1.27 1.27)
			)
			(justify left bottom)
		)
	)
	(label "SD.DAT2"
		(at 133.35 163.83 0)
		(effects
			(font
				(size 1.27 1.27)
			)
			(justify left bottom)
		)
	)
	(label "ETH.TXRX_D_P"
		(at 181.61 80.01 0)
		(effects
			(font
				(size 1.27 1.27)
			)
			(justify left bottom)
		)
	)
	(label "SD.DAT1"
		(at 133.35 161.29 0)
		(effects
			(font
				(size 1.27 1.27)
			)
			(justify left bottom)
		)
	)
	(label "SD.DAT3"
		(at 133.35 153.67 0)
		(effects
			(font
				(size 1.27 1.27)
			)
			(justify left bottom)
		)
	)
	(label "ID.SDA"
		(at 283.21 120.65 180)
		(effects
			(font
				(size 1.27 1.27)
			)
			(justify right bottom)
		)
	)
	(label "ETH.TXRX_A_N"
		(at 233.68 87.63 180)
		(effects
			(font
				(size 1.27 1.27)
			)
			(justify right bottom)
		)
	)
	(label "SD.CMD"
		(at 275.717 153.67 180)
		(effects
			(font
				(size 1.27 1.27)
			)
			(justify right bottom)
		)
	)
	(label "ETH.LED1"
		(at 181.61 97.79 0)
		(effects
			(font
				(size 1.27 1.27)
			)
			(justify left bottom)
		)
	)
	(label "SD.DAT4"
		(at 275.717 161.29 180)
		(effects
			(font
				(size 1.27 1.27)
			)
			(justify right bottom)
		)
	)
	(label "ETH.TXRX_B_P"
		(at 233.68 80.01 180)
		(effects
			(font
				(size 1.27 1.27)
			)
			(justify right bottom)
		)
	)
	(label "ETH.TXRX_A_P"
		(at 233.68 90.17 180)
		(effects
			(font
				(size 1.27 1.27)
			)
			(justify right bottom)
		)
	)
	(label "I^{2}C0.SDA"
		(at 276.225 179.07 180)
		(effects
			(font
				(size 1.27 1.27)
			)
			(justify right bottom)
		)
	)
	(global_label "SPI6_SCLK{slash}RPI_GPIO21"
		(shape input)
		(at 196.85 107.95 180)
		(fields_autoplaced yes)
		(effects
			(font
				(size 1.27 1.27)
			)
			(justify right)
		)
		(property "Intersheetrefs" "${INTERSHEET_REFS}"
			(at 172.0607 107.8706 0)
			(effects
				(font
					(size 1.27 1.27)
				)
				(justify right)
			)
		)
	)
	(global_label "BT_REG_ON"
		(shape input)
		(at 196.85 191.77 180)
		(fields_autoplaced yes)
		(effects
			(font
				(size 1.27 1.27)
			)
			(justify right)
		)
		(property "Intersheetrefs" "${INTERSHEET_REFS}"
			(at 183.914 191.8494 0)
			(effects
				(font
					(size 1.27 1.27)
				)
				(justify right)
			)
		)
	)
	(global_label "UART3_TX{slash}RPI_GPIO04"
		(shape input)
		(at 220.98 143.51 0)
		(fields_autoplaced yes)
		(effects
			(font
				(size 1.27 1.27)
			)
			(justify left)
		)
		(property "Intersheetrefs" "${INTERSHEET_REFS}"
			(at 245.3133 143.51 0)
			(effects
				(font
					(size 1.27 1.27)
				)
				(justify left)
			)
		)
	)
	(global_label "SPI6_CEO_N{slash}RPI_GPIO18"
		(shape input)
		(at 196.85 138.43 180)
		(fields_autoplaced yes)
		(effects
			(font
				(size 1.27 1.27)
			)
			(justify right)
		)
		(property "Intersheetrefs" "${INTERSHEET_REFS}"
			(at 170.7907 138.3506 0)
			(effects
				(font
					(size 1.27 1.27)
				)
				(justify right)
			)
		)
	)
	(global_label "SCL1{slash}RPI_GPIO03"
		(shape input)
		(at 220.98 146.05 0)
		(fields_autoplaced yes)
		(effects
			(font
				(size 1.27 1.27)
			)
			(justify left)
		)
		(property "Intersheetrefs" "${INTERSHEET_REFS}"
			(at 240.4474 145.9706 0)
			(effects
				(font
					(size 1.27 1.27)
				)
				(justify left)
			)
		)
	)
	(global_label "GPIO7"
		(shape input)
		(at 196.85 123.19 180)
		(fields_autoplaced yes)
		(effects
			(font
				(size 1.27 1.27)
			)
			(justify right)
		)
		(property "Intersheetrefs" "${INTERSHEET_REFS}"
			(at 188.7521 123.1106 0)
			(effects
				(font
					(size 1.27 1.27)
				)
				(justify right)
			)
		)
	)
	(global_label "GPIO26"
		(shape input)
		(at 220.98 105.41 0)
		(fields_autoplaced yes)
		(effects
			(font
				(size 1.27 1.27)
			)
			(justify left)
		)
		(property "Intersheetrefs" "${INTERSHEET_REFS}"
			(at 230.2874 105.3306 0)
			(effects
				(font
					(size 1.27 1.27)
				)
				(justify left)
			)
		)
	)
	(global_label "UART3_RX{slash}RPI_GPIO05"
		(shape input)
		(at 220.98 118.11 0)
		(fields_autoplaced yes)
		(effects
			(font
				(size 1.27 1.27)
			)
			(justify left)
		)
		(property "Intersheetrefs" "${INTERSHEET_REFS}"
			(at 245.0436 118.0306 0)
			(effects
				(font
					(size 1.27 1.27)
				)
				(justify left)
			)
		)
	)
	(global_label "UART4_RX{slash}RPI_GPIO09"
		(shape input)
		(at 220.98 125.73 0)
		(fields_autoplaced yes)
		(effects
			(font
				(size 1.27 1.27)
			)
			(justify left)
		)
		(property "Intersheetrefs" "${INTERSHEET_REFS}"
			(at 245.0436 125.6506 0)
			(effects
				(font
					(size 1.27 1.27)
				)
				(justify left)
			)
		)
	)
	(global_label "UART5_TX{slash}RPI_GPIO13"
		(shape input)
		(at 220.98 110.49 0)
		(fields_autoplaced yes)
		(effects
			(font
				(size 1.27 1.27)
			)
			(justify left)
		)
		(property "Intersheetrefs" "${INTERSHEET_REFS}"
			(at 245.3133 110.49 0)
			(effects
				(font
					(size 1.27 1.27)
				)
				(justify left)
			)
		)
	)
	(global_label "SD_VDD_OVERRIDE"
		(shape input)
		(at 196.85 168.91 180)
		(fields_autoplaced yes)
		(effects
			(font
				(size 1.27 1.27)
			)
			(justify right)
		)
		(property "Intersheetrefs" "${INTERSHEET_REFS}"
			(at 176.6896 168.91 0)
			(effects
				(font
					(size 1.27 1.27)
				)
				(justify right)
			)
		)
	)
	(global_label "SDA6{slash}RPI_GPIO22"
		(shape input)
		(at 220.98 133.35 0)
		(fields_autoplaced yes)
		(effects
			(font
				(size 1.27 1.27)
			)
			(justify left)
		)
		(property "Intersheetrefs" "${INTERSHEET_REFS}"
			(at 240.5079 133.2706 0)
			(effects
				(font
					(size 1.27 1.27)
				)
				(justify left)
			)
		)
	)
	(global_label "GPIO10"
		(shape input)
		(at 220.98 130.81 0)
		(fields_autoplaced yes)
		(effects
			(font
				(size 1.27 1.27)
			)
			(justify left)
		)
		(property "Intersheetrefs" "${INTERSHEET_REFS}"
			(at 230.2874 130.7306 0)
			(effects
				(font
					(size 1.27 1.27)
				)
				(justify left)
			)
		)
	)
	(global_label "GPIO17"
		(shape input)
		(at 266.7 137.16 0)
		(fields_autoplaced yes)
		(effects
			(font
				(size 1.27 1.27)
			)
			(justify left)
		)
		(property "Intersheetrefs" "${INTERSHEET_REFS}"
			(at 276.0074 137.0806 0)
			(effects
				(font
					(size 1.27 1.27)
				)
				(justify left)
			)
		)
	)
	(global_label "SDA1{slash}RPI_GPIO02"
		(shape input)
		(at 220.98 148.59 0)
		(fields_autoplaced yes)
		(effects
			(font
				(size 1.27 1.27)
			)
			(justify left)
		)
		(property "Intersheetrefs" "${INTERSHEET_REFS}"
			(at 240.5079 148.5106 0)
			(effects
				(font
					(size 1.27 1.27)
				)
				(justify left)
			)
		)
	)
	(global_label "UART4_TX{slash}RPI_GPIO08"
		(shape input)
		(at 196.85 125.73 180)
		(fields_autoplaced yes)
		(effects
			(font
				(size 1.27 1.27)
			)
			(justify right)
		)
		(property "Intersheetrefs" "${INTERSHEET_REFS}"
			(at 173.0888 125.6506 0)
			(effects
				(font
					(size 1.27 1.27)
				)
				(justify right)
			)
		)
	)
	(global_label "SPI6_MISO{slash}RPI_GPIO19"
		(shape input)
		(at 220.98 107.95 0)
		(fields_autoplaced yes)
		(effects
			(font
				(size 1.27 1.27)
			)
			(justify left)
		)
		(property "Intersheetrefs" "${INTERSHEET_REFS}"
			(at 245.5879 107.8706 0)
			(effects
				(font
					(size 1.27 1.27)
				)
				(justify left)
			)
		)
	)
	(global_label "VBUS"
		(shape input)
		(at 266.7 139.7 0)
		(fields_autoplaced yes)
		(effects
			(font
				(size 1.27 1.27)
			)
			(justify left)
		)
		(property "Intersheetrefs" "${INTERSHEET_REFS}"
			(at 274.5838 139.7 0)
			(effects
				(font
					(size 1.27 1.27)
				)
				(justify left)
			)
		)
	)
	(global_label "GPIO_VREF"
		(shape input)
		(at 220.98 173.99 0)
		(fields_autoplaced yes)
		(effects
			(font
				(size 1.27 1.27)
			)
			(justify left)
		)
		(property "Intersheetrefs" "${INTERSHEET_REFS}"
			(at 233.4321 173.9106 0)
			(effects
				(font
					(size 1.27 1.27)
				)
				(justify left)
			)
		)
	)
	(global_label "SPI6_MOSI{slash}RPI_GPIO20"
		(shape input)
		(at 196.85 110.49 180)
		(fields_autoplaced yes)
		(effects
			(font
				(size 1.27 1.27)
			)
			(justify right)
		)
		(property "Intersheetrefs" "${INTERSHEET_REFS}"
			(at 172.2421 110.4106 0)
			(effects
				(font
					(size 1.27 1.27)
				)
				(justify right)
			)
		)
	)
	(global_label "GPIO6"
		(shape input)
		(at 220.98 113.03 0)
		(fields_autoplaced yes)
		(effects
			(font
				(size 1.27 1.27)
			)
			(justify left)
		)
		(property "Intersheetrefs" "${INTERSHEET_REFS}"
			(at 229.0779 112.9506 0)
			(effects
				(font
					(size 1.27 1.27)
				)
				(justify left)
			)
		)
	)
	(global_label "GPIO24"
		(shape input)
		(at 196.85 133.35 180)
		(effects
			(font
				(size 1.27 1.27)
			)
			(justify right)
		)
		(property "Intersheetrefs" "${INTERSHEET_REFS}"
			(at 187.325 133.35 0)
			(effects
				(font
					(size 1.27 1.27)
				)
				(justify right)
			)
		)
	)
	(global_label "SD_PWR_ON"
		(shape input)
		(at 196.85 171.45 180)
		(fields_autoplaced yes)
		(effects
			(font
				(size 1.27 1.27)
			)
			(justify right)
		)
		(property "Intersheetrefs" "${INTERSHEET_REFS}"
			(at 183.3698 171.3706 0)
			(effects
				(font
					(size 1.27 1.27)
				)
				(justify right)
			)
		)
	)
	(global_label "WL_REG_ON"
		(shape input)
		(at 196.85 189.23 180)
		(fields_autoplaced yes)
		(effects
			(font
				(size 1.27 1.27)
			)
			(justify right)
		)
		(property "Intersheetrefs" "${INTERSHEET_REFS}"
			(at 183.6721 189.3094 0)
			(effects
				(font
					(size 1.27 1.27)
				)
				(justify right)
			)
		)
	)
	(global_label "UART0_TX{slash}RPI_GPIO14"
		(shape input)
		(at 196.85 146.05 180)
		(fields_autoplaced yes)
		(effects
			(font
				(size 1.27 1.27)
			)
			(justify right)
		)
		(property "Intersheetrefs" "${INTERSHEET_REFS}"
			(at 173.0888 145.9706 0)
			(effects
				(font
					(size 1.27 1.27)
				)
				(justify right)
			)
		)
	)
	(global_label "GPIO27"
		(shape input)
		(at 220.98 135.89 0)
		(fields_autoplaced yes)
		(effects
			(font
				(size 1.27 1.27)
			)
			(justify left)
		)
		(property "Intersheetrefs" "${INTERSHEET_REFS}"
			(at 230.2874 135.8106 0)
			(effects
				(font
					(size 1.27 1.27)
				)
				(justify left)
			)
		)
	)
	(global_label "UART0_RX{slash}RPI_GPIO15"
		(shape input)
		(at 196.85 140.97 180)
		(fields_autoplaced yes)
		(effects
			(font
				(size 1.27 1.27)
			)
			(justify right)
		)
		(property "Intersheetrefs" "${INTERSHEET_REFS}"
			(at 172.7864 140.8906 0)
			(effects
				(font
					(size 1.27 1.27)
				)
				(justify right)
			)
		)
	)
	(global_label "UART5_TX{slash}RPI_GPIO12"
		(shape input)
		(at 196.85 115.57 180)
		(fields_autoplaced yes)
		(effects
			(font
				(size 1.27 1.27)
			)
			(justify right)
		)
		(property "Intersheetrefs" "${INTERSHEET_REFS}"
			(at 173.0888 115.4906 0)
			(effects
				(font
					(size 1.27 1.27)
				)
				(justify right)
			)
		)
	)
	(global_label "GPIO11"
		(shape input)
		(at 220.98 123.19 0)
		(fields_autoplaced yes)
		(effects
			(font
				(size 1.27 1.27)
			)
			(justify left)
		)
		(property "Intersheetrefs" "${INTERSHEET_REFS}"
			(at 230.2874 123.1106 0)
			(effects
				(font
					(size 1.27 1.27)
				)
				(justify left)
			)
		)
	)
	(global_label "GPIO25"
		(shape input)
		(at 196.85 128.27 180)
		(fields_autoplaced yes)
		(effects
			(font
				(size 1.27 1.27)
			)
			(justify right)
		)
		(property "Intersheetrefs" "${INTERSHEET_REFS}"
			(at 187.5426 128.1906 0)
			(effects
				(font
					(size 1.27 1.27)
				)
				(justify right)
			)
		)
	)
	(global_label "GLOBAL_EN"
		(shape input)
		(at 196.85 201.93 180)
		(fields_autoplaced yes)
		(effects
			(font
				(size 1.27 1.27)
			)
			(justify right)
		)
		(property "Intersheetrefs" "${INTERSHEET_REFS}"
			(at 183.4024 201.93 0)
			(effects
				(font
					(size 1.27 1.27)
				)
				(justify right)
			)
		)
	)
	(global_label "SCL6{slash}RPI_GPIO23"
		(shape input)
		(at 196.85 135.89 180)
		(fields_autoplaced yes)
		(effects
			(font
				(size 1.27 1.27)
			)
			(justify right)
		)
		(property "Intersheetrefs" "${INTERSHEET_REFS}"
			(at 177.3826 135.8106 0)
			(effects
				(font
					(size 1.27 1.27)
				)
				(justify right)
			)
		)
	)
	(global_label "GPIO16"
		(shape input)
		(at 196.85 113.03 180)
		(fields_autoplaced yes)
		(effects
			(font
				(size 1.27 1.27)
			)
			(justify right)
		)
		(property "Intersheetrefs" "${INTERSHEET_REFS}"
			(at 187.5426 112.9506 0)
			(effects
				(font
					(size 1.27 1.27)
				)
				(justify right)
			)
		)
	)
	(hierarchical_label "ID{I^{2}C}"
		(shape input)
		(at 137.16 115.57 180)
		(effects
			(font
				(size 1.27 1.27)
			)
			(justify right)
		)
	)
	(hierarchical_label "SD{SDIO}"
		(shape input)
		(at 281.94 148.59 0)
		(effects
			(font
				(size 1.27 1.27)
			)
			(justify left)
		)
	)
	(hierarchical_label "SD{SDIO}"
		(shape input)
		(at 127 143.51 180)
		(effects
			(font
				(size 1.27 1.27)
			)
			(justify right)
		)
	)
	(hierarchical_label "ID{I^{2}C}"
		(shape input)
		(at 288.29 115.57 0)
		(effects
			(font
				(size 1.27 1.27)
			)
			(justify left)
		)
	)
	(hierarchical_label "I^{2}C0{I^{2}C}"
		(shape input)
		(at 281.94 171.45 0)
		(effects
			(font
				(size 1.27 1.27)
			)
			(justify left)
		)
	)
	(hierarchical_label "ETH{MDI}"
		(shape input)
		(at 176.53 74.93 180)
		(effects
			(font
				(size 1.27 1.27)
			)
			(justify right)
		)
	)
	(hierarchical_label "ETH{MDI}"
		(shape input)
		(at 238.76 74.93 0)
		(effects
			(font
				(size 1.27 1.27)
			)
			(justify left)
		)
	)
	(symbol
		(lib_id "antmicroResistors0402:R_100k_0402")
		(at 179.07 130.81 0)
		(unit 1)
		(exclude_from_sim no)
		(in_bom yes)
		(on_board yes)
		(dnp no)
		(property "Reference" "R1"
			(at 177.8 129.54 0)
			(effects
				(font
					(size 1.27 1.27)
					(thickness 0.15)
				)
			)
		)
		(property "Value" "R_100k_0402"
			(at 199.39 143.51 0)
			(effects
				(font
					(size 1.27 1.27)
					(thickness 0.15)
				)
				(justify left bottom)
				(hide yes)
			)
		)
		(property "Footprint" "antmicro-footprints:R_0402_1005Metric"
			(at 199.39 146.05 0)
			(effects
				(font
					(size 1.27 1.27)
					(thickness 0.15)
				)
				(justify left bottom)
				(hide yes)
			)
		)
		(property "Datasheet" "https://www.bourns.com/docs/product-datasheets/cr.pdf"
			(at 199.39 148.59 0)
			(effects
				(font
					(size 1.27 1.27)
					(thickness 0.15)
				)
				(justify left bottom)
				(hide yes)
			)
		)
		(property "Description" "SMD Chip Resistor, 100 kohm, ± 1%, 62.5 mW, 0402 [1005 Metric], Thick Film, General Purpose"
			(at 179.07 130.81 0)
			(effects
				(font
					(size 1.27 1.27)
				)
				(hide yes)
			)
		)
		(property "MPN" "CR0402-FX-1003GLF"
			(at 199.39 151.13 0)
			(effects
				(font
					(size 1.27 1.27)
					(thickness 0.15)
				)
				(justify left bottom)
				(hide yes)
			)
		)
		(property "Manufacturer" "Bourns"
			(at 199.39 153.67 0)
			(effects
				(font
					(size 1.27 1.27)
					(thickness 0.15)
				)
				(justify left bottom)
				(hide yes)
			)
		)
		(property "License" "Apache-2.0"
			(at 199.39 156.21 0)
			(effects
				(font
					(size 1.27 1.27)
					(thickness 0.15)
				)
				(justify left bottom)
				(hide yes)
			)
		)
		(property "Author" "Antmicro"
			(at 199.39 158.75 0)
			(effects
				(font
					(size 1.27 1.27)
					(thickness 0.15)
				)
				(justify left bottom)
				(hide yes)
			)
		)
		(property "Val" "100k"
			(at 176.53 132.08 0)
			(effects
				(font
					(size 1.27 1.27)
					(thickness 0.15)
				)
			)
		)
		(property "Tolerance" "1%"
			(at 199.39 140.97 0)
			(effects
				(font
					(size 1.27 1.27)
				)
				(justify left bottom)
				(hide yes)
			)
		)
		(property "Public" ""
			(at 199.39 161.29 0)
			(effects
				(font
					(size 1.27 1.27)
				)
				(justify left bottom)
				(hide yes)
			)
		)
		(pin "1"
		)
		(pin "2"
		)
		(instances
			(project "polarfire-som"
				(path ""
					(reference "R1")
					(unit 1)
				)
			)
		)
	)
	(symbol
		(lib_id "antmicroResistors0402:R_10k_0402")
		(at 261.62 137.16 180)
		(unit 1)
		(exclude_from_sim no)
		(in_bom yes)
		(on_board yes)
		(dnp no)
		(property "Reference" "R13"
			(at 252.73 135.89 0)
			(effects
				(font
					(size 1.27 1.27)
					(thickness 0.15)
				)
				(justify right)
			)
		)
		(property "Value" "R_10k_0402"
			(at 241.3 124.46 0)
			(effects
				(font
					(size 1.27 1.27)
					(thickness 0.15)
				)
				(justify left bottom)
				(hide yes)
			)
		)
		(property "Footprint" "antmicro-footprints:R_0402_1005Metric"
			(at 241.3 121.92 0)
			(effects
				(font
					(size 1.27 1.27)
					(thickness 0.15)
				)
				(justify left bottom)
				(hide yes)
			)
		)
		(property "Datasheet" "https://www.bourns.com/docs/product-datasheets/cr.pdf"
			(at 241.3 119.38 0)
			(effects
				(font
					(size 1.27 1.27)
					(thickness 0.15)
				)
				(justify left bottom)
				(hide yes)
			)
		)
		(property "Description" "SMD Chip Resistor, 10 kohm, ± 1%, 62.5 mW, 0402 [1005 Metric], Thick Film, General Purpose"
			(at 261.62 137.16 0)
			(effects
				(font
					(size 1.27 1.27)
				)
				(hide yes)
			)
		)
		(property "MPN" "CR0402-FX-1002GLF"
			(at 241.3 116.84 0)
			(effects
				(font
					(size 1.27 1.27)
					(thickness 0.15)
				)
				(justify left bottom)
				(hide yes)
			)
		)
		(property "Manufacturer" "Bourns"
			(at 241.3 114.3 0)
			(effects
				(font
					(size 1.27 1.27)
					(thickness 0.15)
				)
				(justify left bottom)
				(hide yes)
			)
		)
		(property "License" "Apache-2.0"
			(at 241.3 111.76 0)
			(effects
				(font
					(size 1.27 1.27)
					(thickness 0.15)
				)
				(justify left bottom)
				(hide yes)
			)
		)
		(property "Author" "Antmicro"
			(at 241.3 109.22 0)
			(effects
				(font
					(size 1.27 1.27)
					(thickness 0.15)
				)
				(justify left bottom)
				(hide yes)
			)
		)
		(property "Val" "10k"
			(at 261.62 135.89 0)
			(effects
				(font
					(size 1.27 1.27)
					(thickness 0.15)
				)
				(justify right)
			)
		)
		(property "Tolerance" "1%"
			(at 241.3 127 0)
			(effects
				(font
					(size 1.27 1.27)
				)
				(justify left bottom)
				(hide yes)
			)
		)
		(property "Public" ""
			(at 241.3 106.68 0)
			(effects
				(font
					(size 1.27 1.27)
				)
				(justify left bottom)
				(hide yes)
			)
		)
		(pin "1"
		)
		(pin "2"
		)
		(instances
			(project "polarfire-som"
				(path ""
					(reference "R13")
					(unit 1)
				)
			)
		)
	)
	(symbol
		(lib_id "antmicropower:+1V8")
		(at 223.52 187.96 270)
		(unit 1)
		(exclude_from_sim no)
		(in_bom yes)
		(on_board yes)
		(dnp no)
		(property "Reference" "#PWR0308"
			(at 220.98 203.2 0)
			(effects
				(font
					(size 1.27 1.27)
					(thickness 0.15)
				)
				(justify left bottom)
				(hide yes)
			)
		)
		(property "Value" "+1V8"
			(at 226.695 187.96 90)
			(effects
				(font
					(size 1.27 1.27)
					(thickness 0.15)
				)
				(justify left)
			)
		)
		(property "Footprint" ""
			(at 215.9 203.2 0)
			(effects
				(font
					(size 1.27 1.27)
					(thickness 0.15)
				)
				(justify left bottom)
				(hide yes)
			)
		)
		(property "Datasheet" ""
			(at 213.36 203.2 0)
			(effects
				(font
					(size 1.27 1.27)
					(thickness 0.15)
				)
				(justify left bottom)
				(hide yes)
			)
		)
		(property "Description" ""
			(at 223.52 187.96 0)
			(effects
				(font
					(size 1.27 1.27)
				)
				(hide yes)
			)
		)
		(property "Author" "Antmicro"
			(at 215.9 203.2 0)
			(effects
				(font
					(size 1.27 1.27)
					(thickness 0.15)
				)
				(justify left bottom)
				(hide yes)
			)
		)
		(property "License" "Apache-2.0"
			(at 213.36 203.2 0)
			(effects
				(font
					(size 1.27 1.27)
					(thickness 0.15)
				)
				(justify left bottom)
				(hide yes)
			)
		)
		(pin "1"
		)
		(instances
			(project "polarfire-som"
				(path ""
					(reference "#PWR0308")
					(unit 1)
				)
			)
		)
	)
	(symbol
		(lib_id "antmicropower:+3V3")
		(at 139.7 187.96 0)
		(unit 1)
		(exclude_from_sim no)
		(in_bom yes)
		(on_board yes)
		(dnp no)
		(fields_autoplaced yes)
		(property "Reference" "#PWR01"
			(at 154.94 187.96 0)
			(effects
				(font
					(size 1.27 1.27)
					(thickness 0.15)
				)
				(justify left bottom)
				(hide yes)
			)
		)
		(property "Value" "+3V3"
			(at 139.7 183.515 0)
			(effects
				(font
					(size 1.27 1.27)
					(thickness 0.15)
				)
			)
		)
		(property "Footprint" ""
			(at 154.94 195.58 0)
			(effects
				(font
					(size 1.27 1.27)
					(thickness 0.15)
				)
				(justify left bottom)
				(hide yes)
			)
		)
		(property "Datasheet" ""
			(at 154.94 198.12 0)
			(effects
				(font
					(size 1.27 1.27)
					(thickness 0.15)
				)
				(justify left bottom)
				(hide yes)
			)
		)
		(property "Description" ""
			(at 139.7 187.96 0)
			(effects
				(font
					(size 1.27 1.27)
				)
				(hide yes)
			)
		)
		(property "Author" "Antmicro"
			(at 154.94 190.5 0)
			(effects
				(font
					(size 1.27 1.27)
					(thickness 0.15)
				)
				(justify left bottom)
				(hide yes)
			)
		)
		(property "License" "Apache-2.0"
			(at 154.94 193.04 0)
			(effects
				(font
					(size 1.27 1.27)
					(thickness 0.15)
				)
				(justify left bottom)
				(hide yes)
			)
		)
		(pin "1"
		)
		(instances
			(project "polarfire-som"
				(path ""
					(reference "#PWR01")
					(unit 1)
				)
			)
		)
	)
	(symbol
		(lib_id "antmicropower:+5V")
		(at 194.31 180.34 90)
		(unit 1)
		(exclude_from_sim no)
		(in_bom yes)
		(on_board yes)
		(dnp no)
		(property "Reference" "#PWR05"
			(at 196.85 165.1 0)
			(effects
				(font
					(size 1.27 1.27)
					(thickness 0.15)
				)
				(justify left bottom)
				(hide yes)
			)
		)
		(property "Value" "+5V"
			(at 189.23 180.34 90)
			(effects
				(font
					(size 1.27 1.27)
					(thickness 0.15)
				)
			)
		)
		(property "Footprint" ""
			(at 201.93 165.1 0)
			(effects
				(font
					(size 1.27 1.27)
					(thickness 0.15)
				)
				(justify left bottom)
				(hide yes)
			)
		)
		(property "Datasheet" ""
			(at 204.47 165.1 0)
			(effects
				(font
					(size 1.27 1.27)
					(thickness 0.15)
				)
				(justify left bottom)
				(hide yes)
			)
		)
		(property "Description" ""
			(at 194.31 180.34 0)
			(effects
				(font
					(size 1.27 1.27)
				)
				(hide yes)
			)
		)
		(property "Author" "Antmicro"
			(at 201.93 165.1 0)
			(effects
				(font
					(size 1.27 1.27)
					(thickness 0.15)
				)
				(justify left bottom)
				(hide yes)
			)
		)
		(property "License" "Apache-2.0"
			(at 204.47 165.1 0)
			(effects
				(font
					(size 1.27 1.27)
					(thickness 0.15)
				)
				(justify left bottom)
				(hide yes)
			)
		)
		(pin "1"
		)
		(instances
			(project "polarfire-som"
				(path ""
					(reference "#PWR05")
					(unit 1)
				)
			)
		)
	)
	(symbol
		(lib_id "antmicroB2BConnectors:Plug_Hirose_DF40_2x50_DF40C-100DP-0.4V")
		(at 201.93 77.47 0)
		(unit 1)
		(exclude_from_sim no)
		(in_bom yes)
		(on_board yes)
		(dnp no)
		(fields_autoplaced yes)
		(property "Reference" "J1"
			(at 208.915 69.85 0)
			(effects
				(font
					(size 1.27 1.27)
					(thickness 0.15)
				)
			)
		)
		(property "Value" "Plug_Hirose_DF40_2x50_DF40C-100DP-0.4V"
			(at 238.76 82.55 0)
			(effects
				(font
					(size 1.27 1.27)
					(thickness 0.15)
				)
				(justify left bottom)
				(hide yes)
			)
		)
		(property "Footprint" "antmicro-footprints:Conn_Plug_Hirose_DF40_2x50_DF40C-100DP-0.4V"
			(at 238.76 85.09 0)
			(effects
				(font
					(size 1.27 1.27)
					(thickness 0.15)
				)
				(justify left bottom)
				(hide yes)
			)
		)
		(property "Datasheet" "https://www.hirose.com/en/product/document?clcode=CL0684-4032-1-51&productname=DF40C-100DP-0.4V(51)&series=DF40&documenttype=2DDrawing&lang=en&documentid=0001001212"
			(at 238.76 87.63 0)
			(effects
				(font
					(size 1.27 1.27)
					(thickness 0.15)
				)
				(justify left bottom)
				(hide yes)
			)
		)
		(property "Description" "Mezzanine Connector, Header, 0.4 mm, 2 Rows, 100 Contacts, Surface Mount, Phosphor Bronze"
			(at 201.93 77.47 0)
			(effects
				(font
					(size 1.27 1.27)
				)
				(hide yes)
			)
		)
		(property "MPN" "DF40C-100DP-0.4V(51)"
			(at 208.915 72.39 0)
			(effects
				(font
					(size 1.27 1.27)
					(thickness 0.15)
				)
			)
		)
		(property "Manufacturer" "Hirose Electric"
			(at 238.76 90.17 0)
			(effects
				(font
					(size 1.27 1.27)
					(thickness 0.15)
				)
				(justify left bottom)
				(hide yes)
			)
		)
		(property "Pitch" "0.4 mm"
			(at 238.76 92.71 0)
			(effects
				(font
					(size 1.27 1.27)
				)
				(justify left bottom)
				(hide yes)
			)
		)
		(property "Author" "Antmicro"
			(at 238.76 95.25 0)
			(effects
				(font
					(size 1.27 1.27)
					(thickness 0.15)
				)
				(justify left bottom)
				(hide yes)
			)
		)
		(property "License" "Apache-2.0"
			(at 238.76 97.79 0)
			(effects
				(font
					(size 1.27 1.27)
					(thickness 0.15)
				)
				(justify left bottom)
				(hide yes)
			)
		)
		(pin "53"
		)
		(pin "57"
		)
		(pin "89"
		)
		(pin "25"
		)
		(pin "67"
		)
		(pin "27"
		)
		(pin "56"
		)
		(pin "79"
		)
		(pin "29"
		)
		(pin "43"
		)
		(pin "93"
		)
		(pin "10"
		)
		(pin "20"
		)
		(pin "19"
		)
		(pin "41"
		)
		(pin "11"
		)
		(pin "100"
		)
		(pin "13"
		)
		(pin "18"
		)
		(pin "40"
		)
		(pin "12"
		)
		(pin "1"
		)
		(pin "22"
		)
		(pin "17"
		)
		(pin "80"
		)
		(pin "64"
		)
		(pin "26"
		)
		(pin "6"
		)
		(pin "87"
		)
		(pin "3"
		)
		(pin "52"
		)
		(pin "35"
		)
		(pin "55"
		)
		(pin "94"
		)
		(pin "76"
		)
		(pin "5"
		)
		(pin "73"
		)
		(pin "71"
		)
		(pin "47"
		)
		(pin "88"
		)
		(pin "95"
		)
		(pin "14"
		)
		(pin "MP"
		)
		(pin "99"
		)
		(pin "85"
		)
		(pin "84"
		)
		(pin "86"
		)
		(pin "24"
		)
		(pin "59"
		)
		(pin "90"
		)
		(pin "77"
		)
		(pin "78"
		)
		(pin "69"
		)
		(pin "65"
		)
		(pin "68"
		)
		(pin "74"
		)
		(pin "60"
		)
		(pin "72"
		)
		(pin "98"
		)
		(pin "66"
		)
		(pin "45"
		)
		(pin "58"
		)
		(pin "50"
		)
		(pin "61"
		)
		(pin "62"
		)
		(pin "44"
		)
		(pin "82"
		)
		(pin "2"
		)
		(pin "96"
		)
		(pin "42"
		)
		(pin "81"
		)
		(pin "63"
		)
		(pin "97"
		)
		(pin "15"
		)
		(pin "16"
		)
		(pin "21"
		)
		(pin "36"
		)
		(pin "38"
		)
		(pin "75"
		)
		(pin "70"
		)
		(pin "8"
		)
		(pin "9"
		)
		(pin "92"
		)
		(pin "32"
		)
		(pin "31"
		)
		(pin "39"
		)
		(pin "33"
		)
		(pin "51"
		)
		(pin "4"
		)
		(pin "54"
		)
		(pin "34"
		)
		(pin "37"
		)
		(pin "28"
		)
		(pin "30"
		)
		(pin "91"
		)
		(pin "23"
		)
		(pin "48"
		)
		(pin "83"
		)
		(pin "7"
		)
		(pin "49"
		)
		(pin "46"
		)
		(instances
			(project "polarfire-som"
				(path ""
					(reference "J1")
					(unit 1)
				)
			)
		)
	)
	(symbol
		(lib_id "antmicropower:GND")
		(at 139.7 210.82 0)
		(unit 1)
		(exclude_from_sim no)
		(in_bom yes)
		(on_board yes)
		(dnp no)
		(fields_autoplaced yes)
		(property "Reference" "#PWR03"
			(at 148.59 213.36 0)
			(effects
				(font
					(size 1.27 1.27)
					(thickness 0.15)
				)
				(justify left bottom)
				(hide yes)
			)
		)
		(property "Value" "GND"
			(at 139.7 215.9 0)
			(effects
				(font
					(size 1.27 1.27)
					(thickness 0.15)
				)
			)
		)
		(property "Footprint" ""
			(at 148.59 218.44 0)
			(effects
				(font
					(size 1.27 1.27)
					(thickness 0.15)
				)
				(justify left bottom)
				(hide yes)
			)
		)
		(property "Datasheet" ""
			(at 148.59 223.52 0)
			(effects
				(font
					(size 1.27 1.27)
					(thickness 0.15)
				)
				(justify left bottom)
				(hide yes)
			)
		)
		(property "Description" ""
			(at 139.7 210.82 0)
			(effects
				(font
					(size 1.27 1.27)
				)
				(hide yes)
			)
		)
		(property "Author" "Antmicro"
			(at 148.59 218.44 0)
			(effects
				(font
					(size 1.27 1.27)
					(thickness 0.15)
				)
				(justify left bottom)
				(hide yes)
			)
		)
		(property "License" "Apache-2.0"
			(at 148.59 220.98 0)
			(effects
				(font
					(size 1.27 1.27)
					(thickness 0.15)
				)
				(justify left bottom)
				(hide yes)
			)
		)
		(pin "1"
		)
		(instances
			(project "polarfire-som"
				(path ""
					(reference "#PWR03")
					(unit 1)
				)
			)
		)
	)
	(symbol
		(lib_id "antmicroResistors0402:R_10k_0402")
		(at 139.7 195.58 90)
		(unit 1)
		(exclude_from_sim no)
		(in_bom yes)
		(on_board yes)
		(dnp no)
		(property "Reference" "R101"
			(at 142.24 191.77 90)
			(effects
				(font
					(size 1.27 1.27)
					(thickness 0.15)
				)
				(justify right)
			)
		)
		(property "Value" "R_10k_0402"
			(at 152.4 175.26 0)
			(effects
				(font
					(size 1.27 1.27)
					(thickness 0.15)
				)
				(justify left bottom)
				(hide yes)
			)
		)
		(property "Footprint" "antmicro-footprints:R_0402_1005Metric"
			(at 154.94 175.26 0)
			(effects
				(font
					(size 1.27 1.27)
					(thickness 0.15)
				)
				(justify left bottom)
				(hide yes)
			)
		)
		(property "Datasheet" "https://www.bourns.com/docs/product-datasheets/cr.pdf"
			(at 157.48 175.26 0)
			(effects
				(font
					(size 1.27 1.27)
					(thickness 0.15)
				)
				(justify left bottom)
				(hide yes)
			)
		)
		(property "Description" "SMD Chip Resistor, 10 kohm, ± 1%, 62.5 mW, 0402 [1005 Metric], Thick Film, General Purpose"
			(at 139.7 195.58 0)
			(effects
				(font
					(size 1.27 1.27)
				)
				(hide yes)
			)
		)
		(property "MPN" "CR0402-FX-1002GLF"
			(at 160.02 175.26 0)
			(effects
				(font
					(size 1.27 1.27)
					(thickness 0.15)
				)
				(justify left bottom)
				(hide yes)
			)
		)
		(property "Manufacturer" "Bourns"
			(at 162.56 175.26 0)
			(effects
				(font
					(size 1.27 1.27)
					(thickness 0.15)
				)
				(justify left bottom)
				(hide yes)
			)
		)
		(property "License" "Apache-2.0"
			(at 165.1 175.26 0)
			(effects
				(font
					(size 1.27 1.27)
					(thickness 0.15)
				)
				(justify left bottom)
				(hide yes)
			)
		)
		(property "Author" "Antmicro"
			(at 167.64 175.26 0)
			(effects
				(font
					(size 1.27 1.27)
					(thickness 0.15)
				)
				(justify left bottom)
				(hide yes)
			)
		)
		(property "Val" "10k"
			(at 142.24 194.31 90)
			(effects
				(font
					(size 1.27 1.27)
					(thickness 0.15)
				)
				(justify right)
			)
		)
		(property "Tolerance" "1%"
			(at 149.86 175.26 0)
			(effects
				(font
					(size 1.27 1.27)
				)
				(justify left bottom)
				(hide yes)
			)
		)
		(property "Public" ""
			(at 170.18 175.26 0)
			(effects
				(font
					(size 1.27 1.27)
				)
				(justify left bottom)
				(hide yes)
			)
		)
		(pin "1"
		)
		(pin "2"
		)
		(instances
			(project "polarfire-som"
				(path ""
					(reference "R101")
					(unit 1)
				)
			)
		)
	)
	(symbol
		(lib_id "antmicropower:GND")
		(at 218.44 208.28 0)
		(unit 1)
		(exclude_from_sim no)
		(in_bom yes)
		(on_board yes)
		(dnp no)
		(fields_autoplaced yes)
		(property "Reference" "#PWR07"
			(at 227.33 210.82 0)
			(effects
				(font
					(size 1.27 1.27)
					(thickness 0.15)
				)
				(justify left bottom)
				(hide yes)
			)
		)
		(property "Value" "GND"
			(at 218.44 213.36 0)
			(effects
				(font
					(size 1.27 1.27)
					(thickness 0.15)
				)
			)
		)
		(property "Footprint" ""
			(at 227.33 215.9 0)
			(effects
				(font
					(size 1.27 1.27)
					(thickness 0.15)
				)
				(justify left bottom)
				(hide yes)
			)
		)
		(property "Datasheet" ""
			(at 227.33 220.98 0)
			(effects
				(font
					(size 1.27 1.27)
					(thickness 0.15)
				)
				(justify left bottom)
				(hide yes)
			)
		)
		(property "Description" ""
			(at 218.44 208.28 0)
			(effects
				(font
					(size 1.27 1.27)
				)
				(hide yes)
			)
		)
		(property "Author" "Antmicro"
			(at 227.33 215.9 0)
			(effects
				(font
					(size 1.27 1.27)
					(thickness 0.15)
				)
				(justify left bottom)
				(hide yes)
			)
		)
		(property "License" "Apache-2.0"
			(at 227.33 218.44 0)
			(effects
				(font
					(size 1.27 1.27)
					(thickness 0.15)
				)
				(justify left bottom)
				(hide yes)
			)
		)
		(pin "1"
		)
		(instances
			(project "polarfire-som"
				(path ""
					(reference "#PWR07")
					(unit 1)
				)
			)
		)
	)
	(symbol
		(lib_id "antmicroResistors0402:R_10k_0402")
		(at 261.62 139.7 180)
		(unit 1)
		(exclude_from_sim no)
		(in_bom yes)
		(on_board yes)
		(dnp yes)
		(property "Reference" "R15"
			(at 252.73 140.97 0)
			(effects
				(font
					(size 1.27 1.27)
					(thickness 0.15)
				)
				(justify right)
			)
		)
		(property "Value" "R_10k_0402"
			(at 241.3 127 0)
			(effects
				(font
					(size 1.27 1.27)
					(thickness 0.15)
				)
				(justify left bottom)
				(hide yes)
			)
		)
		(property "Footprint" "antmicro-footprints:R_0402_1005Metric"
			(at 241.3 124.46 0)
			(effects
				(font
					(size 1.27 1.27)
					(thickness 0.15)
				)
				(justify left bottom)
				(hide yes)
			)
		)
		(property "Datasheet" "https://www.bourns.com/docs/product-datasheets/cr.pdf"
			(at 241.3 121.92 0)
			(effects
				(font
					(size 1.27 1.27)
					(thickness 0.15)
				)
				(justify left bottom)
				(hide yes)
			)
		)
		(property "Description" "SMD Chip Resistor, 10 kohm, ± 1%, 62.5 mW, 0402 [1005 Metric], Thick Film, General Purpose"
			(at 261.62 139.7 0)
			(effects
				(font
					(size 1.27 1.27)
				)
				(hide yes)
			)
		)
		(property "MPN" "CR0402-FX-1002GLF"
			(at 241.3 119.38 0)
			(effects
				(font
					(size 1.27 1.27)
					(thickness 0.15)
				)
				(justify left bottom)
				(hide yes)
			)
		)
		(property "Manufacturer" "Bourns"
			(at 241.3 116.84 0)
			(effects
				(font
					(size 1.27 1.27)
					(thickness 0.15)
				)
				(justify left bottom)
				(hide yes)
			)
		)
		(property "License" "Apache-2.0"
			(at 241.3 114.3 0)
			(effects
				(font
					(size 1.27 1.27)
					(thickness 0.15)
				)
				(justify left bottom)
				(hide yes)
			)
		)
		(property "Author" "Antmicro"
			(at 241.3 111.76 0)
			(effects
				(font
					(size 1.27 1.27)
					(thickness 0.15)
				)
				(justify left bottom)
				(hide yes)
			)
		)
		(property "Val" "10k"
			(at 261.62 140.97 0)
			(effects
				(font
					(size 1.27 1.27)
					(thickness 0.15)
				)
				(justify right)
			)
		)
		(property "Tolerance" "1%"
			(at 241.3 129.54 0)
			(effects
				(font
					(size 1.27 1.27)
				)
				(justify left bottom)
				(hide yes)
			)
		)
		(property "DNP" "DNP"
			(at 259.08 139.7 0)
			(effects
				(font
					(size 1.27 1.27)
				)
				(hide yes)
			)
		)
		(property "Public" ""
			(at 241.3 109.22 0)
			(effects
				(font
					(size 1.27 1.27)
				)
				(justify left bottom)
				(hide yes)
			)
		)
		(pin "1"
		)
		(pin "2"
		)
		(instances
			(project "polarfire-som"
				(path ""
					(reference "R15")
					(unit 1)
				)
			)
		)
	)
	(symbol
		(lib_id "antmicropower:GND")
		(at 199.39 208.28 0)
		(unit 1)
		(exclude_from_sim no)
		(in_bom yes)
		(on_board yes)
		(dnp no)
		(fields_autoplaced yes)
		(property "Reference" "#PWR06"
			(at 208.28 210.82 0)
			(effects
				(font
					(size 1.27 1.27)
					(thickness 0.15)
				)
				(justify left bottom)
				(hide yes)
			)
		)
		(property "Value" "GND"
			(at 199.39 213.36 0)
			(effects
				(font
					(size 1.27 1.27)
					(thickness 0.15)
				)
			)
		)
		(property "Footprint" ""
			(at 208.28 215.9 0)
			(effects
				(font
					(size 1.27 1.27)
					(thickness 0.15)
				)
				(justify left bottom)
				(hide yes)
			)
		)
		(property "Datasheet" ""
			(at 208.28 220.98 0)
			(effects
				(font
					(size 1.27 1.27)
					(thickness 0.15)
				)
				(justify left bottom)
				(hide yes)
			)
		)
		(property "Description" ""
			(at 199.39 208.28 0)
			(effects
				(font
					(size 1.27 1.27)
				)
				(hide yes)
			)
		)
		(property "Author" "Antmicro"
			(at 208.28 215.9 0)
			(effects
				(font
					(size 1.27 1.27)
					(thickness 0.15)
				)
				(justify left bottom)
				(hide yes)
			)
		)
		(property "License" "Apache-2.0"
			(at 208.28 218.44 0)
			(effects
				(font
					(size 1.27 1.27)
					(thickness 0.15)
				)
				(justify left bottom)
				(hide yes)
			)
		)
		(pin "1"
		)
		(instances
			(project "polarfire-som"
				(path ""
					(reference "#PWR06")
					(unit 1)
				)
			)
		)
	)
	(symbol
		(lib_id "antmicroTransistorsFETsMOSFETsSingle:DMG1012T-7")
		(at 133.35 205.74 0)
		(unit 1)
		(exclude_from_sim no)
		(in_bom yes)
		(on_board yes)
		(dnp no)
		(fields_autoplaced yes)
		(property "Reference" "Q2"
			(at 143.51 201.93 0)
			(effects
				(font
					(size 1.27 1.27)
					(thickness 0.15)
				)
				(justify left)
			)
		)
		(property "Value" "DMG1012T-7"
			(at 143.51 209.55 0)
			(effects
				(font
					(size 1.27 1.27)
					(thickness 0.15)
				)
				(justify left bottom)
				(hide yes)
			)
		)
		(property "Footprint" "antmicro-footprints:SOT-523"
			(at 143.51 212.09 0)
			(effects
				(font
					(size 1.27 1.27)
					(thickness 0.15)
				)
				(justify left bottom)
				(hide yes)
			)
		)
		(property "Datasheet" "https://www.diodes.com/assets/Datasheets/ds31783.pdf"
			(at 143.51 214.63 0)
			(effects
				(font
					(size 1.27 1.27)
					(thickness 0.15)
				)
				(justify left bottom)
				(hide yes)
			)
		)
		(property "Description" "Power MOSFET, N Channel, 20 V, 630 mA, 0.3 ohm, SOT-523, Surface Mount"
			(at 133.35 205.74 0)
			(effects
				(font
					(size 1.27 1.27)
				)
				(hide yes)
			)
		)
		(property "MPN" "DMG1012T-7"
			(at 143.51 204.47 0)
			(effects
				(font
					(size 1.27 1.27)
					(thickness 0.15)
				)
				(justify left)
			)
		)
		(property "Manufacturer" "Diodes Incorporated"
			(at 143.51 207.01 0)
			(effects
				(font
					(size 1.27 1.27)
					(thickness 0.15)
				)
				(justify left bottom)
				(hide yes)
			)
		)
		(property "Author" "Antmicro"
			(at 143.51 217.17 0)
			(effects
				(font
					(size 1.27 1.27)
					(thickness 0.15)
				)
				(justify left bottom)
				(hide yes)
			)
		)
		(property "License" "Apache-2.0"
			(at 143.51 219.71 0)
			(effects
				(font
					(size 1.27 1.27)
					(thickness 0.15)
				)
				(justify left bottom)
				(hide yes)
			)
		)
		(property "Public" ""
			(at 153.67 213.36 0)
			(effects
				(font
					(size 1.27 1.27)
				)
				(justify left bottom)
				(hide yes)
			)
		)
		(pin "1"
		)
		(pin "2"
		)
		(pin "3"
		)
		(instances
			(project "polarfire-som"
				(path ""
					(reference "Q2")
					(unit 1)
				)
			)
		)
	)
	(symbol
		(lib_id "antmicropower:VDDI")
		(at 127 204.47 0)
		(unit 1)
		(exclude_from_sim no)
		(in_bom yes)
		(on_board yes)
		(dnp no)
		(fields_autoplaced yes)
		(property "Reference" "#PWR0323"
			(at 127 208.28 0)
			(effects
				(font
					(size 1.27 1.27)
				)
				(hide yes)
			)
		)
		(property "Value" "VDD"
			(at 127 200.025 0)
			(effects
				(font
					(size 1.27 1.27)
				)
			)
		)
		(property "Footprint" ""
			(at 127 204.47 0)
			(effects
				(font
					(size 1.27 1.27)
				)
				(hide yes)
			)
		)
		(property "Datasheet" ""
			(at 127 204.47 0)
			(effects
				(font
					(size 1.27 1.27)
				)
				(hide yes)
			)
		)
		(property "Description" ""
			(at 127 204.47 0)
			(effects
				(font
					(size 1.27 1.27)
				)
				(hide yes)
			)
		)
		(pin "1"
		)
		(instances
			(project "polarfire-som"
				(path ""
					(reference "#PWR0323")
					(unit 1)
				)
			)
		)
	)
	(symbol
		(lib_id "antmicropower:+3V3")
		(at 175.26 130.81 90)
		(unit 1)
		(exclude_from_sim no)
		(in_bom yes)
		(on_board yes)
		(dnp no)
		(property "Reference" "#PWR04"
			(at 177.8 115.57 0)
			(effects
				(font
					(size 1.27 1.27)
					(thickness 0.15)
				)
				(justify left bottom)
				(hide yes)
			)
		)
		(property "Value" "+3V3"
			(at 168.91 130.81 90)
			(effects
				(font
					(size 1.27 1.27)
					(thickness 0.15)
				)
			)
		)
		(property "Footprint" ""
			(at 182.88 115.57 0)
			(effects
				(font
					(size 1.27 1.27)
					(thickness 0.15)
				)
				(justify left bottom)
				(hide yes)
			)
		)
		(property "Datasheet" ""
			(at 185.42 115.57 0)
			(effects
				(font
					(size 1.27 1.27)
					(thickness 0.15)
				)
				(justify left bottom)
				(hide yes)
			)
		)
		(property "Description" ""
			(at 175.26 130.81 0)
			(effects
				(font
					(size 1.27 1.27)
				)
				(hide yes)
			)
		)
		(property "Author" "Antmicro"
			(at 182.88 115.57 0)
			(effects
				(font
					(size 1.27 1.27)
					(thickness 0.15)
				)
				(justify left bottom)
				(hide yes)
			)
		)
		(property "License" "Apache-2.0"
			(at 185.42 115.57 0)
			(effects
				(font
					(size 1.27 1.27)
					(thickness 0.15)
				)
				(justify left bottom)
				(hide yes)
			)
		)
		(pin "1"
		)
		(instances
			(project "polarfire-som"
				(path ""
					(reference "#PWR04")
					(unit 1)
				)
			)
		)
	)
	(symbol
		(lib_id "antmicropower:+3V3")
		(at 223.52 182.88 270)
		(unit 1)
		(exclude_from_sim no)
		(in_bom yes)
		(on_board yes)
		(dnp no)
		(property "Reference" "#PWR0307"
			(at 220.98 198.12 0)
			(effects
				(font
					(size 1.27 1.27)
					(thickness 0.15)
				)
				(justify left bottom)
				(hide yes)
			)
		)
		(property "Value" "+3V3"
			(at 229.235 182.88 90)
			(effects
				(font
					(size 1.27 1.27)
					(thickness 0.15)
				)
			)
		)
		(property "Footprint" ""
			(at 215.9 198.12 0)
			(effects
				(font
					(size 1.27 1.27)
					(thickness 0.15)
				)
				(justify left bottom)
				(hide yes)
			)
		)
		(property "Datasheet" ""
			(at 213.36 198.12 0)
			(effects
				(font
					(size 1.27 1.27)
					(thickness 0.15)
				)
				(justify left bottom)
				(hide yes)
			)
		)
		(property "Description" ""
			(at 223.52 182.88 0)
			(effects
				(font
					(size 1.27 1.27)
				)
				(hide yes)
			)
		)
		(property "Author" "Antmicro"
			(at 215.9 198.12 0)
			(effects
				(font
					(size 1.27 1.27)
					(thickness 0.15)
				)
				(justify left bottom)
				(hide yes)
			)
		)
		(property "License" "Apache-2.0"
			(at 213.36 198.12 0)
			(effects
				(font
					(size 1.27 1.27)
					(thickness 0.15)
				)
				(justify left bottom)
				(hide yes)
			)
		)
		(pin "1"
		)
		(instances
			(project "polarfire-som"
				(path ""
					(reference "#PWR0307")
					(unit 1)
				)
			)
		)
	)
)
